G04 ================== begin FILE IDENTIFICATION RECORD ==================*
G04 Layout Name:  t6mg_pdb_a_v02_0109_1330.brd*
G04 Film Name:    gnd1*
G04 File Format:  Gerber RS274X*
G04 File Origin:  Cadence Allegro 16.3-S038*
G04 Origin Date:  Mon Jan 13 14:11:53 2014*
G04 *
G04 Layer:  DRAWING FORMAT/TITLE_BLOCK*
G04 Layer:  VIA CLASS/GND1*
G04 Layer:  PIN/GND1*
G04 Layer:  MANUFACTURING/PHOTOPLOT_OUTLINE*
G04 Layer:  ETCH/GND1*
G04 Layer:  DRAWING FORMAT/TITLE_DATA_GND1*
G04 *
G04 Offset:    (0.00 0.00)*
G04 Mirror:    No*
G04 Mode:      Negative*
G04 Rotation:  0*
G04 FullContactRelief:  No*
G04 UndefLineWidth:     6.00*
G04 ================== end FILE IDENTIFICATION RECORD ====================*
%FSLAX25Y25*MOIN*%
%IR0*IPPOS*OFA0.00000B0.00000*MIA0B0*SFA1.00000B1.00000*%
%ADD24C,.03*%
%ADD34C,.05*%
%AMMACRO27*
4,1,36,0.0,.01,
-.001736,.009848,
-.00342,.009397,
-.005,.00866,
-.006428,.00766,
-.00766,.006428,
-.00866,.005,
-.009397,.00342,
-.009848,.001736,
-.01,0.0,
-.009848,-.001736,
-.009397,-.00342,
-.00866,-.005,
-.00766,-.006428,
-.006428,-.00766,
-.005,-.00866,
-.00342,-.009397,
-.001736,-.009848,
0.0,-.01,
.001736,-.009848,
.00342,-.009397,
.005,-.00866,
.006428,-.00766,
.00766,-.006428,
.00866,-.005,
.009397,-.00342,
.009848,-.001736,
.01,0.0,
.009848,.001736,
.009397,.00342,
.00866,.005,
.00766,.006428,
.006428,.00766,
.005,.00866,
.00342,.009397,
.001736,.009848,
0.0,.01,
0.0*
%
%ADD27MACRO27*%
%ADD13C,.063*%
%ADD29C,.064*%
%ADD22C,.082*%
%ADD14C,.056*%
%ADD17C,.048*%
%AMMACRO16*
4,1,36,0.0,.004,
.000695,.003939,
.001368,.003759,
.002,.003464,
.002571,.003064,
.003064,.002571,
.003464,.002,
.003759,.001368,
.003939,.000695,
.004,0.0,
.003939,-.000695,
.003759,-.001368,
.003464,-.002,
.003064,-.002571,
.002571,-.003064,
.002,-.003464,
.001368,-.003759,
.000695,-.003939,
0.0,-.004,
-.000695,-.003939,
-.001368,-.003759,
-.002,-.003464,
-.002571,-.003064,
-.003064,-.002571,
-.003464,-.002,
-.003759,-.001368,
-.003939,-.000695,
-.004,0.0,
-.003939,.000695,
-.003759,.001368,
-.003464,.002,
-.003064,.002571,
-.002571,.003064,
-.002,.003464,
-.001368,.003759,
-.000695,.003939,
0.0,.004,
180.*
%
%ADD16MACRO16*%
%ADD25C,.059*%
%ADD20C,.077*%
%AMMACRO12*
4,1,16,.02548,.01487,
.027675,.01022,
.029029,.005259,
.029501,.000138,
.029077,-.004987,
.027769,-.009961,
.025618,-.014631,
.02548,-.01487,
.03056,-.01996,
.033562,-.01435,
.035544,-.008304,
.036446,-.002006,
.03624,.004353,
.034934,.01058,
.032566,.016486,
.03056,.01996,
.02548,.01487,
90.*
4,1,16,.01487,-.02548,
.01022,-.027675,
.005259,-.029029,
.000138,-.029501,
-.004987,-.029077,
-.009961,-.027769,
-.014631,-.025618,
-.01487,-.02548,
-.01996,-.03056,
-.01435,-.033562,
-.008304,-.035544,
-.002006,-.036446,
.004353,-.03624,
.01058,-.034934,
.016486,-.032566,
.01996,-.03056,
.01487,-.02548,
90.*
4,1,16,-.02548,-.01487,
-.027675,-.01022,
-.029029,-.005259,
-.029501,-.000138,
-.029077,.004987,
-.027769,.009961,
-.025618,.014631,
-.02548,.01487,
-.03056,.01996,
-.033562,.01435,
-.035544,.008304,
-.036446,.002006,
-.03624,-.004353,
-.034934,-.01058,
-.032566,-.016486,
-.03056,-.01996,
-.02548,-.01487,
90.*
4,1,16,-.01487,.02548,
-.01022,.027675,
-.005259,.029029,
-.000138,.029501,
.004987,.029077,
.009961,.027769,
.014631,.025618,
.01487,.02548,
.01996,.03056,
.01435,.033562,
.008304,.035544,
.002006,.036446,
-.004353,.03624,
-.01058,.034934,
-.016486,.032566,
-.01996,.03056,
-.01487,.02548,
90.*
%
%ADD12MACRO12*%
%ADD36O,.235X.274*%
%ADD18C,.125*%
%ADD10C,.162*%
%ADD35C,.235*%
%ADD37C,.345*%
%ADD31C,.129*%
%ADD15C,.156*%
%AMMACRO19*
4,1,36,0.0,.013,
-.002257,.012803,
-.004446,.012216,
-.0065,.011258,
-.008356,.009959,
-.009959,.008356,
-.011258,.0065,
-.012216,.004446,
-.012803,.002257,
-.013,0.0,
-.012803,-.002257,
-.012216,-.004446,
-.011258,-.0065,
-.009959,-.008356,
-.008356,-.009959,
-.0065,-.011258,
-.004446,-.012216,
-.002257,-.012803,
0.0,-.013,
.002257,-.012803,
.004446,-.012216,
.0065,-.011258,
.008356,-.009959,
.009959,-.008356,
.011258,-.0065,
.012216,-.004446,
.012803,-.002257,
.013,0.0,
.012803,.002257,
.012216,.004446,
.011258,.0065,
.009959,.008356,
.008356,.009959,
.0065,.011258,
.004446,.012216,
.002257,.012803,
0.0,.013,
270.*
%
%ADD19MACRO19*%
%AMMACRO32*
4,1,36,0.0,.014,
.002431,.013787,
.004788,.013156,
.007,.012124,
.008999,.010725,
.010725,.008999,
.012124,.007,
.013156,.004788,
.013787,.002431,
.014,0.0,
.013787,-.002431,
.013156,-.004788,
.012124,-.007,
.010725,-.008999,
.008999,-.010725,
.007,-.012124,
.004788,-.013156,
.002431,-.013787,
0.0,-.014,
-.002431,-.013787,
-.004788,-.013156,
-.007,-.012124,
-.008999,-.010725,
-.010725,-.008999,
-.012124,-.007,
-.013156,-.004788,
-.013787,-.002431,
-.014,0.0,
-.013787,.002431,
-.013156,.004788,
-.012124,.007,
-.010725,.008999,
-.008999,.010725,
-.007,.012124,
-.004788,.013156,
-.002431,.013787,
0.0,.014,
180.*
%
%ADD32MACRO32*%
%ADD28C,.188*%
%AMMACRO11*
4,1,36,0.0,.004,
.000695,.003939,
.001368,.003759,
.002,.003464,
.002571,.003064,
.003064,.002571,
.003464,.002,
.003759,.001368,
.003939,.000695,
.004,0.0,
.003939,-.000695,
.003759,-.001368,
.003464,-.002,
.003064,-.002571,
.002571,-.003064,
.002,-.003464,
.001368,-.003759,
.000695,-.003939,
0.0,-.004,
-.000695,-.003939,
-.001368,-.003759,
-.002,-.003464,
-.002571,-.003064,
-.003064,-.002571,
-.003464,-.002,
-.003759,-.001368,
-.003939,-.000695,
-.004,0.0,
-.003939,.000695,
-.003759,.001368,
-.003464,.002,
-.003064,.002571,
-.002571,.003064,
-.002,.003464,
-.001368,.003759,
-.000695,.003939,
0.0,.004,
0.0*
%
%ADD11MACRO11*%
%AMMACRO30*
4,1,16,.02584,.01524,
.028094,.010521,
.029494,.005483,
.029998,.000278,
.029591,-.004935,
.028284,-.009999,
.026118,-.014758,
.02584,-.01524,
.03092,-.02032,
.033979,-.014642,
.036005,-.008519,
.036938,-.002138,
.036748,.004309,
.035441,.010625,
.033058,.016618,
.03092,.02032,
.02584,.01524,
270.*
4,1,16,.01524,-.02584,
.010521,-.028094,
.005483,-.029494,
.000278,-.029998,
-.004935,-.029591,
-.009999,-.028284,
-.014758,-.026118,
-.01524,-.02584,
-.02032,-.03092,
-.014642,-.033979,
-.008519,-.036005,
-.002138,-.036938,
.004309,-.036748,
.010625,-.035441,
.016618,-.033058,
.02032,-.03092,
.01524,-.02584,
270.*
4,1,16,-.02584,-.01524,
-.028094,-.010521,
-.029494,-.005483,
-.029998,-.000278,
-.029591,.004935,
-.028284,.009999,
-.026118,.014758,
-.02584,.01524,
-.03092,.02032,
-.033979,.014642,
-.036005,.008519,
-.036938,.002138,
-.036748,-.004309,
-.035441,-.010625,
-.033058,-.016618,
-.03092,-.02032,
-.02584,-.01524,
270.*
4,1,16,-.01524,.02584,
-.010521,.028094,
-.005483,.029494,
-.000278,.029998,
.004935,.029591,
.009999,.028284,
.014758,.026118,
.01524,.02584,
.02032,.03092,
.014642,.033979,
.008519,.036005,
.002138,.036938,
-.004309,.036748,
-.010625,.035441,
-.016618,.033058,
-.02032,.03092,
-.01524,.02584,
270.*
%
%ADD30MACRO30*%
%AMMACRO33*
4,1,15,.02291,.0123,
.024698,.008135,
.025735,.003723,
.025991,-.000803,
.025456,-.005304,
.024149,-.009644,
.02291,-.0123,
.02803,-.01742,
.030629,-.012288,
.032298,-.006783,
.032985,-.001071,
.03267,.004673,
.031362,.010275,
.029101,.015565,
.02803,.01742,
.02291,.0123,
180.*
4,1,15,.0123,-.02291,
.008135,-.024698,
.003723,-.025735,
-.000803,-.025991,
-.005304,-.025456,
-.009644,-.024149,
-.0123,-.02291,
-.01742,-.02803,
-.012288,-.030629,
-.006783,-.032298,
-.001071,-.032985,
.004673,-.03267,
.010275,-.031362,
.015565,-.029101,
.01742,-.02803,
.0123,-.02291,
180.*
4,1,15,-.02291,-.0123,
-.024698,-.008135,
-.025735,-.003723,
-.025991,.000803,
-.025456,.005304,
-.024149,.009644,
-.02291,.0123,
-.02803,.01742,
-.030629,.012288,
-.032298,.006783,
-.032985,.001071,
-.03267,-.004673,
-.031362,-.010275,
-.029101,-.015565,
-.02803,-.01742,
-.02291,-.0123,
180.*
4,1,15,-.0123,.02291,
-.008135,.024698,
-.003723,.025735,
.000803,.025991,
.005304,.025456,
.009644,.024149,
.0123,.02291,
.01742,.02803,
.012288,.030629,
.006783,.032298,
.001071,.032985,
-.004673,.03267,
-.010275,.031362,
-.015565,.029101,
-.01742,.02803,
-.0123,.02291,
180.*
%
%ADD33MACRO33*%
%AMMACRO26*
4,1,15,.02401,.0134,
.025972,.009027,
.027145,.00438,
.027493,-.0004,
.027006,-.005168,
.025698,-.009779,
.02401,-.0134,
.02912,-.01851,
.031892,-.013172,
.033695,-.007434,
.034474,-.00147,
.034205,.004538,
.032897,.010409,
.03059,.015964,
.02912,.01851,
.02401,.0134,
270.*
4,1,15,.0134,-.02401,
.009027,-.025972,
.00438,-.027145,
-.0004,-.027493,
-.005168,-.027006,
-.009779,-.025698,
-.0134,-.02401,
-.01851,-.02912,
-.013172,-.031892,
-.007434,-.033695,
-.00147,-.034474,
.004538,-.034205,
.010409,-.032897,
.015964,-.03059,
.01851,-.02912,
.0134,-.02401,
270.*
4,1,15,-.02401,-.0134,
-.025972,-.009027,
-.027145,-.00438,
-.027493,.0004,
-.027006,.005168,
-.025698,.009779,
-.02401,.0134,
-.02912,.01851,
-.031892,.013172,
-.033695,.007434,
-.034474,.00147,
-.034205,-.004538,
-.032897,-.010409,
-.03059,-.015964,
-.02912,-.01851,
-.02401,-.0134,
270.*
4,1,15,-.0134,.02401,
-.009027,.025972,
-.00438,.027145,
.0004,.027493,
.005168,.027006,
.009779,.025698,
.0134,.02401,
.01851,.02912,
.013172,.031892,
.007434,.033695,
.00147,.034474,
-.004538,.034205,
-.010409,.032897,
-.015964,.03059,
-.01851,.02912,
-.0134,.02401,
270.*
%
%ADD26MACRO26*%
%AMMACRO21*
4,1,17,.03056,.01996,
.033562,.01435,
.035544,.008304,
.036446,.002006,
.03624,-.004353,
.034934,-.01058,
.032566,-.016486,
.03056,-.01996,
.0356,-.025,
.0394,-.018438,
.042004,-.011316,
.043331,-.003851,
.043341,.003732,
.042034,.011201,
.039451,.018331,
.035668,.024903,
.0356,.025,
.03056,.01996,
270.*
4,1,17,.01996,-.03056,
.01435,-.033562,
.008304,-.035544,
.002006,-.036446,
-.004353,-.03624,
-.01058,-.034934,
-.016486,-.032566,
-.01996,-.03056,
-.025,-.0356,
-.018438,-.0394,
-.011316,-.042004,
-.003851,-.043331,
.003732,-.043341,
.011201,-.042034,
.018331,-.039451,
.024903,-.035668,
.025,-.0356,
.01996,-.03056,
270.*
4,1,17,-.03056,-.01996,
-.033562,-.01435,
-.035544,-.008304,
-.036446,-.002006,
-.03624,.004353,
-.034934,.01058,
-.032566,.016486,
-.03056,.01996,
-.0356,.025,
-.0394,.018438,
-.042004,.011316,
-.043331,.003851,
-.043341,-.003732,
-.042034,-.011201,
-.039451,-.018331,
-.035668,-.024903,
-.0356,-.025,
-.03056,-.01996,
270.*
4,1,17,-.01996,.03056,
-.01435,.033562,
-.008304,.035544,
-.002006,.036446,
.004353,.03624,
.01058,.034934,
.016486,.032566,
.01996,.03056,
.025,.0356,
.018438,.0394,
.011316,.042004,
.003851,.043331,
-.003732,.043341,
-.011201,.042034,
-.018331,.039451,
-.024903,.035668,
-.025,.0356,
-.01996,.03056,
270.*
%
%ADD21MACRO21*%
%AMMACRO23*
4,1,17,.03273,.02212,
.036074,.0161,
.038322,.009592,
.039405,.002791,
.039291,-.004094,
.037983,-.010854,
.035521,-.017285,
.03273,-.02212,
.03775,-.02715,
.041891,-.020182,
.044759,-.012601,
.046267,-.004638,
.04637,.003467,
.045063,.011466,
.042388,.019117,
.038424,.026188,
.03775,.02715,
.03273,.02212,
270.*
4,1,17,.02212,-.03273,
.0161,-.036074,
.009592,-.038322,
.002791,-.039405,
-.004094,-.039291,
-.010854,-.037983,
-.017285,-.035521,
-.02212,-.03273,
-.02715,-.03775,
-.020182,-.041891,
-.012601,-.044759,
-.004638,-.046267,
.003467,-.04637,
.011466,-.045063,
.019117,-.042388,
.026188,-.038424,
.02715,-.03775,
.02212,-.03273,
270.*
4,1,17,-.03273,-.02212,
-.036074,-.0161,
-.038322,-.009592,
-.039405,-.002791,
-.039291,.004094,
-.037983,.010854,
-.035521,.017285,
-.03273,.02212,
-.03775,.02715,
-.041891,.020182,
-.044759,.012601,
-.046267,.004638,
-.04637,-.003467,
-.045063,-.011466,
-.042388,-.019117,
-.038424,-.026188,
-.03775,-.02715,
-.03273,-.02212,
270.*
4,1,17,-.02212,.03273,
-.0161,.036074,
-.009592,.038322,
-.002791,.039405,
.004094,.039291,
.010854,.037983,
.017285,.035521,
.02212,.03273,
.02715,.03775,
.020182,.041891,
.012601,.044759,
.004638,.046267,
-.003467,.04637,
-.011466,.045063,
-.019117,.042388,
-.026188,.038424,
-.02715,.03775,
-.02212,.03273,
270.*
%
%ADD23MACRO23*%
%ADD38C,.006*%
%ADD41C,.08409*%
%ADD43C,.24506*%
%ADD39C,.16406*%
%ADD45C,.13266*%
%ADD44C,.35606*%
%ADD40C,.15806*%
%ADD42C,.19786*%
G75*
%LPD*%
G75*
G36*
G01X-723776Y-489221D02*
X1782976D01*
Y2987387D01*
X-723776D01*
Y-489221D01*
G37*
%LPC*%
G75*
G36*
G01X5906Y17752D02*
G02X2004Y21654I0J3902D01*
G01Y2064961D01*
G02X5905Y2068862I3901J0D01*
G01X92520D01*
G03X100429Y2076772I-1J7910D01*
G01Y2080709D01*
G02X104331Y2084610I3902J-1D01*
G01X397638D01*
G02X403508Y2078740I0J-5870D01*
G01Y7874D01*
G02X397638Y2004I-5870J0D01*
G01X104331D01*
G02X100429Y5906I0J3902D01*
G01Y9843D01*
G03X92520Y17752I-7909J0D01*
G01X5906D01*
G37*
%LPD*%
G75*
G36*
G01X17980Y1347510D02*
Y1348455D01*
X17981D01*
G02X22973Y1348450I2490J-5857D01*
G01X22974D01*
Y1347505D01*
G03X23213Y1347078I500J0D01*
G02X23859Y1346612I-2741J-4480D01*
G01X25411D01*
X25412Y1346611D01*
G02X14107Y1342598I-4940J-4013D01*
G02X15507Y1346580I6365J-1D01*
G01X17048D01*
G02X17740Y1347083I3424J-3982D01*
G03X17980Y1347510I-260J427D01*
G37*
G36*
G01X17976Y989245D02*
Y990190D01*
X17977D01*
G02X22969Y990185I2490J-5857D01*
G01X22970D01*
Y989240D01*
G03X23209Y988813I500J0D01*
G02X23856Y988346I-2741J-4480D01*
G01X25408D01*
G02X14103Y984333I-4940J-4013D01*
G02X15503Y988316I6365J0D01*
G01X17045D01*
G02X17736Y988818I3422J-3984D01*
G03X17976Y989245I-260J427D01*
G37*
G36*
G01X170004Y727205D02*
G02X156767Y727182I-6619J0D01*
G02X169983Y727726I6618J30D01*
G02X169986Y727689I-6594J-553D01*
G02X170004Y727205I-6600J-488D01*
G37*
G36*
G01Y552205D02*
G02X156767Y552182I-6619J0D01*
G02X169983Y552726I6618J30D01*
G02X169986Y552689I-6594J-553D01*
G02X170004Y552205I-6600J-488D01*
G37*
G36*
G01X169982Y1952727D02*
G02X170003Y1952205I-6597J-527D01*
G02X156766I-6618J0D01*
G02X169982Y1952727I6618J0D01*
G37*
G36*
G01X294833Y1881121D02*
X294834Y1885021D01*
G02X307086Y1897273I12252J0D01*
G02X319338Y1885021I0J-12252D01*
G01Y1881121D01*
G02X307086Y1868869I-12252J0D01*
G01Y1868868D01*
G02X294833Y1881121I0J12253D01*
G37*
G36*
G01X169982Y1777727D02*
G02X170003Y1777205I-6597J-527D01*
G02X156766I-6618J0D01*
G02X169982Y1777727I6618J0D01*
G37*
G36*
G01Y1602727D02*
G02X170003Y1602205I-6597J-527D01*
G02X156766I-6618J0D01*
G02X169982Y1602727I6618J0D01*
G37*
G36*
G01Y1427727D02*
G02X170003Y1427205I-6597J-527D01*
G02X156766I-6618J0D01*
G02X169982Y1427727I6618J0D01*
G37*
G36*
G01Y1252727D02*
G02X170003Y1252205I-6597J-527D01*
G02X156766I-6618J0D01*
G02X169982Y1252727I6618J0D01*
G37*
G36*
G01Y1077727D02*
G02X170003Y1077205I-6597J-527D01*
G02X156766I-6618J0D01*
G02X169982Y1077727I6618J0D01*
G37*
G36*
G01X26828Y1054605D02*
G02X20471Y1060962I-6357J0D01*
G01Y1060963D01*
X20472D01*
G02X26828Y1054605I-1J-6357D01*
G37*
G36*
G01X169982Y902727D02*
G02X170003Y902205I-6597J-527D01*
G02X156766I-6618J0D01*
G02X169982Y902727I6618J0D01*
G37*
G36*
G01Y377727D02*
G02X170002Y377205I-6597J-514D01*
G02X156766I-6618J0D01*
G02X169982Y377727I6618J0D01*
G37*
G36*
G01Y202727D02*
G02X170002Y202205I-6597J-514D01*
G02X156766I-6618J0D01*
G02X169982Y202727I6618J0D01*
G37*
G36*
G01Y27727D02*
G02X170002Y27205I-6597J-514D01*
G02X156766I-6618J0D01*
G02X169982Y27727I6618J0D01*
G37*
G54D41*
X30473Y102007D03*
Y137440D03*
X30197Y305027D03*
Y352271D03*
X30473Y1855008D03*
Y1890441D03*
Y1937007D03*
Y1972440D03*
Y2012007D03*
Y2047440D03*
G54D43*
X307086Y308267D03*
G54D39*
X29979Y30500D03*
Y75500D03*
Y166500D03*
Y211500D03*
Y239500D03*
Y284500D03*
Y375500D03*
Y420500D03*
G54D45*
X373385Y32520D03*
Y207520D03*
Y382520D03*
X373386Y557520D03*
Y732520D03*
X373385Y907520D03*
Y1082520D03*
Y1257520D03*
Y1432520D03*
Y1607520D03*
Y1782520D03*
Y1957520D03*
G54D44*
X359842Y78780D03*
Y253780D03*
Y428779D03*
Y603779D03*
Y778780D03*
Y953780D03*
Y1128779D03*
Y1303780D03*
Y1478780D03*
Y1653780D03*
Y1828779D03*
Y2003780D03*
G54D40*
X30254Y514500D03*
Y559500D03*
Y1572504D03*
Y1617504D03*
G54D42*
X65354Y114960D03*
Y464960D03*
Y814960D03*
Y1164960D03*
Y1514960D03*
Y1864960D03*
X307086Y127165D03*
Y477165D03*
Y827165D03*
Y1343504D03*
Y1693504D03*
X307087Y2043503D03*
G54D24*
X48433Y866179D03*
X48467Y869278D03*
X49441Y1238962D03*
X45581Y1278420D03*
X45413Y1283724D03*
X45244Y1289067D03*
X45350Y1299697D03*
X45267Y1294203D03*
X45281Y1310893D03*
X45244Y1305787D03*
X46980Y1335843D03*
Y1325843D03*
Y1315843D03*
Y1320843D03*
Y1330843D03*
Y1345843D03*
Y1340843D03*
X57124Y675327D03*
X54483Y679810D03*
X59236Y670758D03*
X70865Y872278D03*
Y866278D03*
Y860278D03*
Y897750D03*
Y890116D03*
X60815Y1019026D03*
X63577Y1019115D03*
X59127Y1257647D03*
X58356Y1279812D03*
X58416Y1272383D03*
X61866Y1309190D03*
X54543Y1308995D03*
X67568Y1307829D03*
X70340Y1328203D03*
X61866Y1342104D03*
X93223Y417736D03*
X94347Y421562D03*
X96308Y696622D03*
X95775Y751469D03*
X89338Y878294D03*
X91733Y899382D03*
X92633Y907404D03*
X91294Y926951D03*
X98139Y990959D03*
X76446Y1014871D03*
X79499D03*
X82763Y1060051D03*
X96684Y1081791D03*
X96510Y1395382D03*
X95236Y1453321D03*
X80376Y1772098D03*
Y1768566D03*
Y1775609D03*
X106958Y26285D03*
X101430Y41803D03*
X107405Y49898D03*
X107037Y34687D03*
X104350Y62293D03*
X107263Y72244D03*
X109054Y58250D03*
X108672Y86150D03*
X106836Y376461D03*
X106709Y391219D03*
X105451Y406795D03*
X114498Y396207D03*
X109475Y434743D03*
X111017Y419566D03*
X102960Y672823D03*
X113018Y706356D03*
X107025Y725368D03*
X105087Y754126D03*
X106935Y745139D03*
X107173Y735219D03*
X112836Y769122D03*
X111967Y795261D03*
X115139Y849240D03*
X105395Y972040D03*
X102611Y972220D03*
X100687Y999391D03*
X107351Y1093484D03*
X107235Y1081791D03*
X107215Y1072208D03*
X108779Y1105760D03*
X105152Y1118381D03*
X112503Y1115860D03*
X108468Y1129286D03*
X100719Y1312810D03*
Y1306810D03*
Y1330810D03*
Y1336810D03*
Y1324810D03*
Y1318810D03*
Y1346065D03*
X106962Y1434041D03*
X106921Y1419492D03*
X106763Y1444599D03*
X107006Y1452651D03*
X108574Y1463389D03*
X113518Y1489571D03*
X107355Y1770437D03*
X107391Y1794460D03*
X107220Y1791589D03*
X107373Y1780544D03*
X108819Y1812118D03*
X106819Y1802230D03*
X108819Y1824470D03*
X144878Y1738861D03*
X157558Y51426D03*
X161339Y88108D03*
X159417Y91281D03*
X158901Y85017D03*
X168975Y265783D03*
X165975D03*
X168975Y296140D03*
Y286803D03*
Y276298D03*
X165975D03*
Y286803D03*
Y296140D03*
X168975Y312307D03*
Y303868D03*
X165975D03*
Y312307D03*
X156865Y401207D03*
X161517Y436119D03*
X159019Y439268D03*
X158807Y432969D03*
X157272Y604773D03*
X160272D03*
X157272Y633416D03*
Y613574D03*
Y624079D03*
X160272D03*
Y613574D03*
Y633416D03*
X157272Y641144D03*
Y649583D03*
X160272D03*
Y641144D03*
X156610Y751063D03*
X158956Y780982D03*
X161479Y784141D03*
X159053Y787280D03*
X163699Y972924D03*
X166699D03*
X163699Y983439D03*
Y993944D03*
X166699D03*
Y983439D03*
X163424Y1011298D03*
Y1003570D03*
Y1019737D03*
X166424D03*
Y1003570D03*
Y1011298D03*
X156854Y1101031D03*
X159382Y1136151D03*
X158456Y1129045D03*
X158749Y1307733D03*
X155749D03*
X158749Y1328753D03*
Y1318248D03*
X155749D03*
Y1328753D03*
X158749Y1354257D03*
Y1338090D03*
Y1345818D03*
X155749D03*
Y1338090D03*
Y1354257D03*
X158618Y1399448D03*
X164037Y1400226D03*
X170351Y1401324D03*
X159192Y1451105D03*
X159216Y1477124D03*
X159526Y1483434D03*
X161492Y1667763D03*
Y1657248D03*
X158492D03*
Y1667763D03*
X161492Y1695333D03*
Y1687605D03*
Y1678268D03*
X158492D03*
Y1687605D03*
Y1695333D03*
X161492Y1703772D03*
X158492D03*
X163257Y1737619D03*
X150309Y1737009D03*
X168151Y1739208D03*
X165782Y1732903D03*
X156183Y1735240D03*
X156452Y1800821D03*
X161844Y1828225D03*
X159822Y1831380D03*
X159075Y1825087D03*
X175989Y944537D03*
X176011Y936829D03*
X175359Y963486D03*
X175561Y955964D03*
X175135Y972490D03*
X175022Y980281D03*
X175742Y989958D03*
X175449Y997660D03*
X175698Y1008730D03*
X175473Y1016296D03*
X175448Y1031766D03*
X175897Y1023997D03*
X176083Y1402321D03*
X173394Y1736051D03*
X217732Y153964D03*
Y170131D03*
Y161692D03*
Y164692D03*
Y173131D03*
Y156964D03*
X219214Y1287272D03*
Y1301975D03*
X219349Y1308924D03*
X219214Y1294491D03*
X219178Y1324285D03*
Y1332321D03*
Y1316842D03*
Y1339840D03*
X238741Y153964D03*
X227700D03*
X238741Y170131D03*
Y161692D03*
X227700Y170131D03*
Y161692D03*
Y164692D03*
Y173131D03*
X238741Y164692D03*
Y173131D03*
X227700Y156964D03*
X238741D03*
X239746Y407393D03*
Y396878D03*
Y417898D03*
Y399878D03*
Y410393D03*
Y420898D03*
X234012Y754782D03*
X237012D03*
X234012Y762510D03*
Y770949D03*
X237012D03*
Y762510D03*
X241396Y862887D03*
Y855159D03*
Y871326D03*
X238396D03*
Y855159D03*
Y862887D03*
X235709Y1124900D03*
Y1135415D03*
X232709D03*
Y1124900D03*
X242677Y1135415D03*
Y1124900D03*
X235709Y1145920D03*
X232709D03*
X242677D03*
X226642Y1287272D03*
X222214D03*
X229642D03*
X226642Y1301975D03*
X235465D03*
X226777Y1308924D03*
X235600D03*
X242961Y1301975D03*
X243096Y1308924D03*
X226642Y1294491D03*
X235465D03*
X242961D03*
X222214D03*
X222349Y1308924D03*
X222214Y1301975D03*
X238465Y1294491D03*
X229642D03*
X238600Y1308924D03*
X229777D03*
X238465Y1301975D03*
X229642D03*
X226606Y1324285D03*
X235429D03*
X226606Y1332321D03*
X235429D03*
X242925Y1324285D03*
Y1332321D03*
X226606Y1316842D03*
X235429D03*
X242925D03*
X222178D03*
Y1332321D03*
Y1324285D03*
X238429Y1316842D03*
X229606D03*
X238429Y1332321D03*
X229606D03*
X238429Y1324285D03*
X229606D03*
X226606Y1339840D03*
X235429D03*
X242925D03*
X222178D03*
X238429D03*
X229606D03*
X226573Y2031480D03*
X236541D03*
X226573Y2020965D03*
X236541D03*
X242582D03*
Y2031480D03*
X231541Y2020965D03*
X221573D03*
X231541Y2031480D03*
X221573D03*
X226573Y2059050D03*
X236541Y2051322D03*
Y2059050D03*
X226573Y2041985D03*
Y2051322D03*
X236541Y2041985D03*
X242582Y2059050D03*
Y2051322D03*
Y2041985D03*
X231541D03*
X221573Y2051322D03*
Y2041985D03*
X231541Y2059050D03*
Y2051322D03*
X221573Y2059050D03*
X236541Y2067489D03*
X226573D03*
X242582D03*
X221573D03*
X231541D03*
X256566Y54944D03*
X264104D03*
X256566Y45572D03*
X264104D03*
Y48572D03*
X256566D03*
Y65449D03*
X264104D03*
Y57944D03*
X256566D03*
X264104Y68449D03*
X256566D03*
X256947Y128276D03*
X257125Y115559D03*
X256861Y153964D03*
X248083D03*
X256861Y170131D03*
Y161692D03*
X248083Y170131D03*
Y161692D03*
Y164692D03*
Y173131D03*
X256861Y164692D03*
Y173131D03*
X248083Y156964D03*
X256861D03*
X264596Y221664D03*
X252818D03*
X255818D03*
X261596D03*
X264596Y242684D03*
Y232179D03*
X252818Y242684D03*
Y232179D03*
X255818D03*
Y242684D03*
X261596Y232179D03*
Y242684D03*
X264596Y268188D03*
Y259749D03*
Y252021D03*
X252818Y268188D03*
Y252021D03*
Y259749D03*
X255818D03*
Y252021D03*
Y268188D03*
X261596Y252021D03*
Y259749D03*
Y268188D03*
X266040Y407146D03*
Y396631D03*
Y417651D03*
X257572Y396630D03*
Y407145D03*
X248714Y407536D03*
Y397021D03*
X257572Y417650D03*
X248714Y418041D03*
Y400021D03*
Y410536D03*
X257572Y410145D03*
Y399630D03*
X266040Y399631D03*
Y410146D03*
X248714Y421041D03*
X257572Y420650D03*
X266040Y420651D03*
X265722Y463102D03*
X265737Y473680D03*
X267166Y581440D03*
Y572639D03*
X264166D03*
Y581440D03*
X267166Y609010D03*
Y601282D03*
Y591945D03*
X264166D03*
Y601282D03*
Y609010D03*
X267166Y617449D03*
X264166D03*
X243980Y754782D03*
X255021D03*
X258021D03*
X246980D03*
X243980Y762510D03*
Y770949D03*
X255021Y762510D03*
Y770949D03*
X258021D03*
Y762510D03*
X246980Y770949D03*
Y762510D03*
X255837Y823626D03*
X255687Y812192D03*
X253174Y855159D03*
Y862887D03*
Y871326D03*
X250174D03*
Y862887D03*
Y855159D03*
X265766Y949344D03*
X262766D03*
X265766Y967106D03*
Y959859D03*
X265621Y974386D03*
X262621D03*
X262766Y959859D03*
Y967106D03*
X265621Y990553D03*
Y982114D03*
X262621D03*
Y990553D03*
X263473Y1124613D03*
Y1135128D03*
X245677Y1124900D03*
Y1135415D03*
X254433Y1135271D03*
Y1124756D03*
X251433D03*
Y1135271D03*
X260473Y1135128D03*
Y1124613D03*
X263473Y1145633D03*
X245677Y1145920D03*
X254433Y1145776D03*
X251433D03*
X260473Y1145633D03*
X259581Y1272430D03*
Y1282945D03*
X256581D03*
Y1272430D03*
X267622D03*
Y1282945D03*
X245961Y1294491D03*
X246096Y1308924D03*
X245961Y1301975D03*
X259581Y1293450D03*
Y1302787D03*
Y1310515D03*
X256581D03*
Y1302787D03*
Y1293450D03*
X267622Y1310515D03*
Y1302787D03*
Y1293450D03*
X245925Y1316842D03*
Y1332321D03*
Y1324285D03*
X259581Y1318954D03*
X256581D03*
X267622D03*
X245925Y1339840D03*
X260939Y1548010D03*
Y1534139D03*
Y1541055D03*
X263939D03*
Y1534139D03*
Y1548010D03*
X258564Y1621823D03*
X261564D03*
X258564Y1642843D03*
Y1632338D03*
X261564D03*
Y1642843D03*
X258564Y1668347D03*
Y1659908D03*
Y1652180D03*
X261564D03*
Y1659908D03*
Y1668347D03*
X262759Y1697613D03*
Y1676593D03*
Y1687108D03*
X251718Y1697613D03*
Y1687108D03*
Y1676593D03*
X254718D03*
Y1687108D03*
X265759D03*
Y1676593D03*
X254718Y1697613D03*
X265759D03*
X262498Y1722140D03*
X262759Y1714678D03*
Y1706950D03*
X251457Y1722140D03*
X251718Y1714678D03*
Y1706950D03*
X265759D03*
X254718D03*
Y1714678D03*
X265759D03*
X265498Y1722140D03*
X254457D03*
X261639Y1819074D03*
Y1812119D03*
Y1805203D03*
X253468Y1819074D03*
Y1812119D03*
Y1805203D03*
X267396Y1812122D03*
Y1805206D03*
Y1819077D03*
X250468Y1805203D03*
Y1812119D03*
Y1819074D03*
X258639Y1805203D03*
Y1812119D03*
Y1819074D03*
X261459Y1826219D03*
X253288D03*
X261459Y1840090D03*
Y1833135D03*
X253288D03*
Y1840090D03*
X250288D03*
Y1833135D03*
X267037Y1840093D03*
Y1833138D03*
X258459Y1833135D03*
Y1840090D03*
X267037Y1826222D03*
X250288Y1826219D03*
X258459D03*
X247582Y2031480D03*
Y2020965D03*
X260337D03*
Y2031480D03*
X267115Y2020965D03*
Y2031480D03*
X255337D03*
Y2020965D03*
X247582Y2041985D03*
Y2051322D03*
Y2059050D03*
X260337Y2051322D03*
Y2059050D03*
Y2041985D03*
X267115D03*
Y2059050D03*
Y2051322D03*
X255337Y2041985D03*
Y2059050D03*
Y2051322D03*
X260337Y2067489D03*
X247582D03*
X267115D03*
X255337D03*
X288102Y54944D03*
Y45572D03*
X271572Y54944D03*
X279754D03*
X271572Y45572D03*
X279754D03*
Y48572D03*
X271572D03*
X288102D03*
Y65449D03*
X271572D03*
X279754D03*
Y57944D03*
X271572D03*
X288102D03*
X279754Y68449D03*
X271572D03*
X288102D03*
X274531Y407289D03*
Y396774D03*
Y417794D03*
Y399774D03*
Y410289D03*
Y420794D03*
X289569Y532762D03*
Y516595D03*
Y524323D03*
X278944Y581440D03*
Y572639D03*
X275944D03*
Y581440D03*
X278944Y601282D03*
Y609010D03*
Y591945D03*
X275944D03*
Y609010D03*
Y601282D03*
X278944Y617449D03*
X275944D03*
X277544Y949344D03*
X274544D03*
X277544Y967106D03*
Y959859D03*
X277399Y974386D03*
X274399D03*
X274544Y959859D03*
Y967106D03*
X277399Y990553D03*
Y982114D03*
X274399D03*
Y990553D03*
X272821Y1124471D03*
Y1134986D03*
X269821D03*
Y1124471D03*
X272821Y1145491D03*
X269821D03*
X284182Y1184455D03*
Y1192183D03*
X287182D03*
Y1184455D03*
X284182Y1200622D03*
X287182D03*
X270622Y1282945D03*
Y1272430D03*
Y1293450D03*
Y1302787D03*
Y1310515D03*
Y1318954D03*
X275400Y1548190D03*
X268534Y1548010D03*
X282995Y1548190D03*
X275400Y1534319D03*
Y1541235D03*
X268534Y1534139D03*
Y1541055D03*
X282995Y1534319D03*
Y1541235D03*
X285995D03*
Y1534319D03*
X271534Y1541055D03*
Y1534139D03*
X278400Y1541235D03*
Y1534319D03*
X285995Y1548190D03*
X271534Y1548010D03*
X278400Y1548190D03*
X270342Y1621823D03*
X273342D03*
X270342Y1642843D03*
Y1632338D03*
X273342D03*
Y1642843D03*
X270342Y1668347D03*
Y1652180D03*
Y1659908D03*
X273342D03*
Y1652180D03*
Y1668347D03*
X270396Y1819077D03*
Y1805206D03*
Y1812122D03*
X270037Y1826222D03*
Y1833138D03*
Y1840093D03*
X280240Y1858668D03*
X279976Y1864565D03*
X272115Y2031480D03*
Y2020965D03*
Y2051322D03*
Y2059050D03*
Y2041985D03*
Y2067489D03*
X308057Y248863D03*
X306267Y241010D03*
X314914Y238162D03*
X314940Y252083D03*
X300537Y516309D03*
X307966Y516419D03*
Y524147D03*
X300537Y524037D03*
Y532476D03*
X307966Y532586D03*
X292569Y524323D03*
Y516595D03*
Y532762D03*
X304966Y532586D03*
X297537Y532476D03*
Y524037D03*
X304966Y524147D03*
Y516419D03*
X297537Y516309D03*
X313791Y532871D03*
Y516704D03*
Y524432D03*
X315187Y652457D03*
X304146D03*
X307146D03*
X315187Y661258D03*
X304146D03*
Y681100D03*
X315187D03*
Y671763D03*
X304146D03*
X307146D03*
Y681100D03*
Y661258D03*
X315187Y688828D03*
X304146D03*
Y697267D03*
X315187D03*
X307146D03*
Y688828D03*
X310194Y1020657D03*
X310078Y1007303D03*
X310274Y1001286D03*
X310143Y1014094D03*
X307143D03*
X307274Y1001286D03*
X307078Y1007303D03*
X307194Y1020657D03*
X310129Y1027081D03*
X309999Y1033718D03*
X306999D03*
X307129Y1027081D03*
X309678Y1053262D03*
X312527Y1162266D03*
X309159Y1184526D03*
Y1192254D03*
X300691Y1184526D03*
X292721Y1184312D03*
Y1192040D03*
X300691Y1192254D03*
X303691D03*
X295721Y1192040D03*
Y1184312D03*
X303691Y1184526D03*
X312159Y1192254D03*
Y1184526D03*
X312698Y1172804D03*
X309159Y1200693D03*
X300691D03*
X292721Y1200479D03*
X295721D03*
X303691Y1200693D03*
X312159D03*
X314183Y1403423D03*
X312823Y1472957D03*
X312464Y1480102D03*
X312823Y1466002D03*
Y1459086D03*
X295715Y1480099D03*
X295895Y1472954D03*
X304066D03*
X303886Y1480099D03*
X295895Y1459083D03*
Y1465999D03*
X304066D03*
Y1459083D03*
X301066D03*
Y1465999D03*
X292895D03*
Y1459083D03*
X300886Y1480099D03*
X301066Y1472954D03*
X292895D03*
X292715Y1480099D03*
X309823Y1459086D03*
Y1466002D03*
X309464Y1480102D03*
X309823Y1472957D03*
X312464Y1493973D03*
Y1487018D03*
X295715Y1487015D03*
Y1493970D03*
X303886D03*
Y1487015D03*
X300886D03*
Y1493970D03*
X292715D03*
Y1487015D03*
X309464Y1487018D03*
Y1493973D03*
X302267Y1524401D03*
X301734Y1513883D03*
X312077Y1575871D03*
X292614Y1864565D03*
X295754Y1917148D03*
X303349D03*
X295754Y1910232D03*
X303349D03*
X310215Y1910412D03*
X314810D03*
X307215D03*
X300349Y1910232D03*
X292754D03*
X300349Y1917148D03*
X292754D03*
X310215Y1917328D03*
X295754Y1924103D03*
X303349D03*
X310215Y1924283D03*
X307215D03*
X314810D03*
X300349Y1924103D03*
X292754D03*
X307215Y1917328D03*
X314810D03*
X331403Y51409D03*
X333889Y56021D03*
X338227Y61559D03*
X320372Y225979D03*
X318088Y231820D03*
X321899Y238137D03*
X331046Y232021D03*
X320961Y250105D03*
X324709Y231580D03*
X332775Y318634D03*
X332693Y311980D03*
X329693D03*
X329775Y318634D03*
X332775Y335272D03*
Y342461D03*
Y325935D03*
X329775D03*
Y342461D03*
Y335272D03*
X332685Y348655D03*
X329685D03*
X335522Y404033D03*
X323313Y418313D03*
X326196Y413982D03*
X328950Y409216D03*
X320980Y423225D03*
X325139Y516632D03*
Y524360D03*
X316791Y524432D03*
Y516704D03*
Y532871D03*
X325139Y532799D03*
X322139D03*
Y524360D03*
Y516632D03*
X336617Y577978D03*
X319305Y582111D03*
X329636Y584715D03*
X317724Y588250D03*
X337387Y586230D03*
X320380Y576491D03*
X331867Y589810D03*
X333750Y595326D03*
X321742Y599041D03*
X318187Y652457D03*
Y671763D03*
Y681100D03*
Y661258D03*
Y697267D03*
Y688828D03*
X331568Y752967D03*
X339012Y752859D03*
X329336Y762693D03*
X334010Y758588D03*
X327524Y758020D03*
X329938Y948756D03*
X332527Y943746D03*
X324098Y946104D03*
X318557Y941178D03*
X323868Y929978D03*
X326646Y939788D03*
X336160Y937262D03*
X328583Y933262D03*
X321425Y951577D03*
X321235Y1020657D03*
X321315Y1001286D03*
X321119Y1007303D03*
X321184Y1014094D03*
X318184D03*
X318119Y1007303D03*
X318315Y1001286D03*
X318235Y1020657D03*
X321170Y1027081D03*
X321040Y1033718D03*
X318040D03*
X318170Y1027081D03*
X324246Y1051786D03*
X335677Y1048904D03*
X317592Y1053050D03*
X337509Y1109598D03*
X328989Y1121090D03*
X326558Y1126368D03*
X317936Y1192253D03*
Y1184525D03*
X320936D03*
Y1192253D03*
X323403Y1172804D03*
X317936Y1200692D03*
X320936D03*
X327452Y1279447D03*
X321978Y1282086D03*
X329619Y1284016D03*
X327932Y1289221D03*
X325636Y1399114D03*
X334646Y1400804D03*
X323720Y1570924D03*
X333474Y1566686D03*
X335963Y1573797D03*
X323813Y1753231D03*
X329887Y1752081D03*
X317810Y1910412D03*
X332399Y1926787D03*
X317810Y1917328D03*
Y1924283D03*
X359931Y52189D03*
X348289Y50863D03*
X345089Y56190D03*
X340373Y51579D03*
X343816Y318634D03*
X343734Y311980D03*
X340734D03*
X340816Y318634D03*
X343816Y335272D03*
Y342461D03*
Y325935D03*
X340816D03*
Y342461D03*
Y335272D03*
X362236Y324983D03*
X343726Y348655D03*
X340726D03*
X342097Y401684D03*
X363825Y401768D03*
X342900Y580126D03*
X356559Y675167D03*
X362577Y752783D03*
X344109Y751809D03*
X343656Y933725D03*
X345578Y1047844D03*
X344099Y1106798D03*
X344130Y1401670D03*
X350690Y1403243D03*
X348710Y1570187D03*
X361011Y1568890D03*
X343402Y1572080D03*
X348245Y1575241D03*
X355364Y1570990D03*
X345537Y1916558D03*
X344402Y1911123D03*
X363361Y1918313D03*
X358318Y1920680D03*
X363411Y1923459D03*
X340336Y1922409D03*
X372204Y56126D03*
X379257Y52158D03*
X387524Y76847D03*
X374442Y406857D03*
X374542Y401282D03*
X368907Y404308D03*
X376654Y754748D03*
X382892Y767710D03*
X386790Y774338D03*
X379335Y1189778D03*
X383276Y1184136D03*
X386816Y1179841D03*
X376472Y1194999D03*
X373674Y1199967D03*
X371523Y1204725D03*
X374681Y1365620D03*
X367829Y1566108D03*
X366306Y1899864D03*
X374431Y1901397D03*
X374775Y1919243D03*
X379403Y1917261D03*
X369748Y1921795D03*
G54D34*
X253385Y21890D03*
Y32520D03*
X263385Y21890D03*
Y32520D03*
X253385Y196890D03*
X263385D03*
X253385Y207520D03*
X263385D03*
X253385Y371890D03*
X263385D03*
X253385Y382520D03*
X263385D03*
X253386Y546890D03*
Y557520D03*
X263386Y546890D03*
Y557520D03*
X253386Y721890D03*
Y732520D03*
X263386Y721890D03*
Y732520D03*
X253385Y896890D03*
X263385D03*
X253385Y907520D03*
X263385D03*
X253385Y1071890D03*
X263385D03*
X253385Y1082520D03*
X263385D03*
X253385Y1246890D03*
Y1257520D03*
X263385Y1246890D03*
Y1257520D03*
X253385Y1421890D03*
Y1432520D03*
X263385Y1421890D03*
Y1432520D03*
X253385Y1596890D03*
X263385D03*
X253385Y1607520D03*
X263385D03*
X253385Y1771890D03*
X263385D03*
X253385Y1782520D03*
X263385D03*
X253385Y1946890D03*
Y1957520D03*
X263385Y1946890D03*
Y1957520D03*
X273385Y21890D03*
Y32520D03*
X283385Y21890D03*
Y32520D03*
X273385Y196890D03*
X283385D03*
X273385Y207520D03*
X283385D03*
X273385Y371890D03*
X283385D03*
X273385Y382520D03*
X283385D03*
X273386Y546890D03*
Y557520D03*
X283386Y546890D03*
Y557520D03*
X273386Y721890D03*
Y732520D03*
X283386Y721890D03*
Y732520D03*
X273385Y896890D03*
X283385D03*
X273385Y907520D03*
X283385D03*
X273385Y1071890D03*
X283385D03*
X273385Y1082520D03*
X283385D03*
X273385Y1246890D03*
Y1257520D03*
X283385Y1246890D03*
Y1257520D03*
X273385Y1421890D03*
Y1432520D03*
X283385Y1421890D03*
Y1432520D03*
X273385Y1596890D03*
X283385D03*
X273385Y1607520D03*
X283385D03*
X273385Y1771890D03*
X283385D03*
X273385Y1782520D03*
X283385D03*
X273385Y1946890D03*
Y1957520D03*
X283385Y1946890D03*
Y1957520D03*
X293385Y21890D03*
Y32520D03*
X303385Y21890D03*
Y32520D03*
X313385D03*
Y21890D03*
X293385Y196890D03*
X303385D03*
X313385D03*
X293385Y207520D03*
X303385D03*
X313385D03*
X293385Y371890D03*
X303385D03*
X313385D03*
X293385Y382520D03*
X303385D03*
X313385D03*
X293386Y546890D03*
Y557520D03*
X303386Y546890D03*
Y557520D03*
X313386D03*
Y546890D03*
X293386Y721890D03*
Y732520D03*
X303386Y721890D03*
Y732520D03*
X313386D03*
Y721890D03*
X293385Y896890D03*
X303385D03*
X313385D03*
X293385Y907520D03*
X303385D03*
X313385D03*
X293385Y1071890D03*
X303385D03*
X313385D03*
X293385Y1082520D03*
X303385D03*
X313385D03*
X293385Y1246890D03*
Y1257520D03*
X303385Y1246890D03*
Y1257520D03*
X313385D03*
Y1246890D03*
X293385Y1421890D03*
Y1432520D03*
X303385Y1421890D03*
Y1432520D03*
X313385D03*
Y1421890D03*
X293385Y1596890D03*
X303385D03*
X313385D03*
X293385Y1607520D03*
X303385D03*
X313385D03*
X293385Y1771890D03*
X303385D03*
X313385D03*
X293385Y1782520D03*
X303385D03*
X313385D03*
X293385Y1946890D03*
Y1957520D03*
X303385Y1946890D03*
Y1957520D03*
X313385D03*
Y1946890D03*
X337165Y24705D03*
X323385Y32520D03*
Y21890D03*
X337165Y34705D03*
Y199705D03*
X323385Y196890D03*
X337165Y209705D03*
X323385Y207520D03*
Y371890D03*
X337165Y374705D03*
Y384705D03*
X323385Y382520D03*
X337166Y549705D03*
Y559705D03*
X323386Y557520D03*
Y546890D03*
X337166Y724705D03*
X323386Y732520D03*
Y721890D03*
X337166Y734705D03*
X337165Y899705D03*
X323385Y896890D03*
X337165Y909705D03*
X323385Y907520D03*
Y1071890D03*
X337165Y1074705D03*
Y1084705D03*
X323385Y1082520D03*
X337165Y1249705D03*
Y1259705D03*
X323385Y1257520D03*
Y1246890D03*
X337165Y1424705D03*
Y1434705D03*
X323385Y1432520D03*
Y1421890D03*
X337165Y1599705D03*
X323385Y1596890D03*
X337165Y1609705D03*
X323385Y1607520D03*
Y1771890D03*
X337165Y1774705D03*
Y1784705D03*
X323385Y1782520D03*
X337165Y1949705D03*
Y1959705D03*
X323385Y1957520D03*
Y1946890D03*
X342165Y19705D03*
Y29705D03*
X347165Y24705D03*
X352165Y19705D03*
Y29705D03*
X357165Y24705D03*
X362165Y19705D03*
Y29705D03*
X347165Y34705D03*
X357165D03*
X342165Y194705D03*
X347165Y199705D03*
X352165Y194705D03*
X357165Y199705D03*
X362165Y194705D03*
X342165Y204705D03*
X347165Y209705D03*
X352165Y204705D03*
X357165Y209705D03*
X362165Y204705D03*
X342165Y369705D03*
X352165D03*
X362165D03*
X342165Y379705D03*
X347165Y374705D03*
Y384705D03*
X352165Y379705D03*
X357165Y374705D03*
Y384705D03*
X362165Y379705D03*
X342166Y544705D03*
Y554705D03*
X347166Y549705D03*
Y559705D03*
X352166Y544705D03*
Y554705D03*
X357166Y549705D03*
Y559705D03*
X362166Y544705D03*
Y554705D03*
X342166Y719705D03*
Y729705D03*
X347166Y724705D03*
X352166Y719705D03*
Y729705D03*
X357166Y724705D03*
X362166Y719705D03*
Y729705D03*
X347166Y734705D03*
X357166D03*
X342165Y894705D03*
X347165Y899705D03*
X352165Y894705D03*
X357165Y899705D03*
X362165Y894705D03*
X342165Y904705D03*
X347165Y909705D03*
X352165Y904705D03*
X357165Y909705D03*
X362165Y904705D03*
X342165Y1069705D03*
X352165D03*
X362165D03*
X342165Y1079705D03*
X347165Y1074705D03*
Y1084705D03*
X352165Y1079705D03*
X357165Y1074705D03*
Y1084705D03*
X362165Y1079705D03*
X342165Y1244705D03*
Y1254705D03*
X347165Y1249705D03*
Y1259705D03*
X352165Y1244705D03*
Y1254705D03*
X357165Y1249705D03*
Y1259705D03*
X362165Y1244705D03*
Y1254705D03*
X342165Y1419705D03*
Y1429705D03*
X347165Y1424705D03*
Y1434705D03*
X352165Y1419705D03*
Y1429705D03*
X357165Y1424705D03*
Y1434705D03*
X362165Y1419705D03*
Y1429705D03*
X342165Y1594705D03*
X347165Y1599705D03*
X352165Y1594705D03*
X357165Y1599705D03*
X362165Y1594705D03*
X342165Y1604705D03*
X347165Y1609705D03*
X352165Y1604705D03*
X357165Y1609705D03*
X362165Y1604705D03*
X342165Y1769705D03*
X352165D03*
X362165D03*
X342165Y1779705D03*
X347165Y1774705D03*
Y1784705D03*
X352165Y1779705D03*
X357165Y1774705D03*
Y1784705D03*
X362165Y1779705D03*
X342165Y1944705D03*
Y1954705D03*
X347165Y1949705D03*
Y1959705D03*
X352165Y1944705D03*
Y1954705D03*
X357165Y1949705D03*
Y1959705D03*
X362165Y1944705D03*
Y1954705D03*
G54D27*
X65354Y101180D03*
X55511Y105117D03*
X51574Y114960D03*
X55511Y124803D03*
X65354Y128740D03*
Y451180D03*
X55511Y455117D03*
X51574Y464960D03*
X55511Y474803D03*
X65354Y478740D03*
Y801180D03*
X55511Y805117D03*
X51574Y814960D03*
X55511Y824803D03*
X65354Y828740D03*
Y1151180D03*
X55511Y1155117D03*
X51574Y1164960D03*
X55511Y1174803D03*
X65354Y1178740D03*
Y1501180D03*
X55511Y1505117D03*
X51574Y1514960D03*
X55511Y1524803D03*
X65354Y1528740D03*
Y1851180D03*
X55511Y1855117D03*
X51574Y1864960D03*
X55511Y1874803D03*
X65354Y1878740D03*
X75197Y105117D03*
Y124803D03*
X79134Y114960D03*
Y464960D03*
X75197Y455117D03*
Y474803D03*
Y805117D03*
Y824803D03*
X79134Y814960D03*
Y1164960D03*
X75197Y1155117D03*
Y1174803D03*
Y1505117D03*
Y1524803D03*
X79134Y1514960D03*
Y1864960D03*
X75197Y1855117D03*
Y1874803D03*
X307086Y113385D03*
X297243Y117322D03*
X293306Y127165D03*
X297243Y137008D03*
X307086Y140945D03*
Y463385D03*
X297243Y467322D03*
X293306Y477165D03*
X297243Y487008D03*
X307086Y490945D03*
Y813385D03*
X297243Y817322D03*
X293306Y827165D03*
X297243Y837008D03*
X307086Y840945D03*
Y1329724D03*
X297243Y1333661D03*
X293306Y1343504D03*
X297243Y1353347D03*
X307086Y1357284D03*
Y1679724D03*
X297243Y1683661D03*
X293306Y1693504D03*
X297243Y1703347D03*
X307086Y1707284D03*
X307087Y2029723D03*
X297244Y2033660D03*
X293307Y2043503D03*
X297244Y2053346D03*
X307087Y2057283D03*
X320866Y127165D03*
X316929Y117322D03*
Y137008D03*
Y467322D03*
Y487008D03*
X320866Y477165D03*
Y827165D03*
X316929Y817322D03*
Y837008D03*
Y1333661D03*
Y1353347D03*
X320866Y1343504D03*
Y1693504D03*
X316929Y1683661D03*
Y1703347D03*
X316930Y2033660D03*
Y2053346D03*
X320867Y2043503D03*
G54D13*
X22756Y125629D03*
X22480Y328649D03*
X22756Y1878630D03*
Y1960629D03*
Y2035629D03*
G54D22*
X30473Y102007D03*
Y137440D03*
X30197Y305027D03*
Y352271D03*
X30473Y1855008D03*
Y1890441D03*
Y1937007D03*
Y1972440D03*
Y2012007D03*
Y2047440D03*
G54D29*
X119920Y18071D03*
Y28071D03*
Y38071D03*
Y48071D03*
Y58071D03*
Y68071D03*
Y78071D03*
Y88071D03*
Y218071D03*
Y228071D03*
Y238071D03*
Y248071D03*
Y258071D03*
Y268071D03*
Y278071D03*
Y288071D03*
Y298071D03*
Y308071D03*
Y318071D03*
Y328071D03*
Y366102D03*
Y376102D03*
Y386102D03*
Y396102D03*
Y406102D03*
Y416102D03*
Y426102D03*
Y436102D03*
Y566102D03*
Y576102D03*
Y586102D03*
Y596102D03*
Y606102D03*
Y616102D03*
Y626102D03*
Y636102D03*
Y646102D03*
Y656102D03*
Y666102D03*
Y676102D03*
Y714134D03*
Y724134D03*
Y734134D03*
Y744134D03*
Y754134D03*
Y764134D03*
Y774134D03*
Y784134D03*
Y914134D03*
Y924134D03*
Y934134D03*
Y944134D03*
Y954134D03*
Y964134D03*
Y974134D03*
Y984134D03*
Y994134D03*
Y1004134D03*
Y1014134D03*
Y1024134D03*
Y1062165D03*
Y1072165D03*
Y1082165D03*
Y1092165D03*
Y1102165D03*
Y1112165D03*
Y1122165D03*
Y1132165D03*
Y1262165D03*
Y1272165D03*
Y1282165D03*
Y1292165D03*
Y1302165D03*
Y1312165D03*
Y1322165D03*
Y1332165D03*
Y1342165D03*
Y1352165D03*
Y1362165D03*
Y1372165D03*
Y1410197D03*
Y1420197D03*
Y1430197D03*
Y1440197D03*
Y1450197D03*
Y1460197D03*
Y1470197D03*
Y1480197D03*
Y1610197D03*
Y1620197D03*
Y1630197D03*
Y1640197D03*
Y1650197D03*
Y1660197D03*
Y1670197D03*
Y1680197D03*
Y1690197D03*
Y1700197D03*
Y1710197D03*
Y1720197D03*
Y1758228D03*
Y1768228D03*
Y1778228D03*
Y1788228D03*
Y1798228D03*
Y1808228D03*
Y1818228D03*
Y1828228D03*
Y1958228D03*
Y1968228D03*
Y1978228D03*
Y1988228D03*
Y1998228D03*
Y2008228D03*
Y2018228D03*
Y2028228D03*
Y2038228D03*
Y2048228D03*
Y2058228D03*
Y2068228D03*
X139920Y28071D03*
Y18071D03*
Y58071D03*
Y48071D03*
Y38071D03*
Y78071D03*
Y68071D03*
Y88071D03*
Y228071D03*
Y218071D03*
Y248071D03*
Y238071D03*
Y268071D03*
Y258071D03*
Y298071D03*
Y288071D03*
Y278071D03*
Y318071D03*
Y308071D03*
Y328071D03*
Y366102D03*
Y396102D03*
Y386102D03*
Y376102D03*
Y416102D03*
Y406102D03*
Y436102D03*
Y426102D03*
Y566102D03*
Y586102D03*
Y576102D03*
Y606102D03*
Y596102D03*
Y636102D03*
Y626102D03*
Y616102D03*
Y656102D03*
Y646102D03*
Y676102D03*
Y666102D03*
Y734134D03*
Y724134D03*
Y714134D03*
Y754134D03*
Y744134D03*
Y774134D03*
Y764134D03*
Y784134D03*
Y924134D03*
Y914134D03*
Y944134D03*
Y934134D03*
Y974134D03*
Y964134D03*
Y954134D03*
Y994134D03*
Y984134D03*
Y1024134D03*
Y1014134D03*
Y1004134D03*
Y1072165D03*
Y1062165D03*
Y1092165D03*
Y1082165D03*
Y1122165D03*
Y1112165D03*
Y1102165D03*
Y1132165D03*
Y1262165D03*
Y1282165D03*
Y1272165D03*
Y1312165D03*
Y1302165D03*
Y1292165D03*
Y1332165D03*
Y1322165D03*
Y1362165D03*
Y1352165D03*
Y1342165D03*
Y1372165D03*
Y1410197D03*
Y1430197D03*
Y1420197D03*
Y1460197D03*
Y1450197D03*
Y1440197D03*
Y1480197D03*
Y1470197D03*
Y1620197D03*
Y1610197D03*
Y1650197D03*
Y1640197D03*
Y1630197D03*
Y1670197D03*
Y1660197D03*
Y1700197D03*
Y1690197D03*
Y1680197D03*
Y1720197D03*
Y1710197D03*
Y1768228D03*
Y1758228D03*
Y1798228D03*
Y1788228D03*
Y1778228D03*
Y1818228D03*
Y1808228D03*
Y1828228D03*
Y1958228D03*
Y1988228D03*
Y1978228D03*
Y1968228D03*
Y2008228D03*
Y1998228D03*
Y2038228D03*
Y2028228D03*
Y2018228D03*
Y2058228D03*
Y2048228D03*
Y2068228D03*
G54D14*
X14073Y512197D03*
Y522000D03*
Y552000D03*
Y561803D03*
Y1580004D03*
Y1570201D03*
Y1610004D03*
Y1619807D03*
X65254Y519500D03*
Y529500D03*
Y539500D03*
X55254Y524500D03*
Y534500D03*
X65254Y549500D03*
X55254Y544500D03*
Y554500D03*
X65254Y1577504D03*
Y1587504D03*
Y1597504D03*
X55254Y1582504D03*
Y1592504D03*
Y1602504D03*
X65254Y1607504D03*
X55254Y1612504D03*
X203542Y73105D03*
X204069Y152050D03*
X204137Y247568D03*
X204597Y331786D03*
X203541Y421732D03*
X204333Y506517D03*
X206668Y598130D03*
X204596Y681645D03*
X205626Y774526D03*
X205386Y856244D03*
X210091Y947202D03*
X209296Y1032544D03*
X205030Y1122856D03*
X205122Y1206233D03*
X205626Y1299104D03*
X204332Y1380966D03*
X203243Y1474162D03*
X204859Y1557277D03*
X205923Y1648177D03*
X205387Y1731351D03*
X205310Y1823227D03*
X204069Y1900420D03*
X205905Y1998730D03*
X205310Y2043388D03*
G54D17*
X15547Y707364D03*
X25389D03*
X7673Y703427D03*
X15547Y715238D03*
Y730986D03*
X25389Y715238D03*
Y730986D03*
X7673Y711301D03*
Y719175D03*
Y727049D03*
X15547Y738860D03*
Y754608D03*
X25389Y738860D03*
Y754608D03*
X7673Y742797D03*
Y750671D03*
Y758545D03*
X15547Y762483D03*
Y770357D03*
Y778231D03*
X25389Y762483D03*
Y770357D03*
Y778231D03*
X7673Y774293D03*
Y782167D03*
X15547Y786105D03*
Y801853D03*
X25389Y786105D03*
Y801853D03*
X7673Y790041D03*
Y797915D03*
Y805790D03*
X15547Y809727D03*
Y817601D03*
X25389Y809727D03*
Y817601D03*
X7673Y813664D03*
Y821538D03*
Y829412D03*
X15547Y833349D03*
Y841223D03*
Y849097D03*
X25389Y833349D03*
Y841223D03*
Y849097D03*
X7673Y837286D03*
Y845160D03*
X15547Y856971D03*
Y872719D03*
X25389Y856971D03*
Y864845D03*
X7673Y860908D03*
Y868782D03*
Y876656D03*
X15547Y880593D03*
Y888467D03*
Y896341D03*
X25389Y880593D03*
Y888467D03*
Y896341D03*
X7673Y892404D03*
Y900278D03*
X15547Y912089D03*
Y919963D03*
X25389Y904215D03*
Y919963D03*
X7673Y908152D03*
Y916026D03*
X15547Y927837D03*
Y935711D03*
Y951459D03*
X25389Y927837D03*
Y935711D03*
Y943585D03*
X7673Y931774D03*
Y939648D03*
Y947522D03*
X15547Y959333D03*
Y967207D03*
Y975081D03*
X25389Y959333D03*
Y967207D03*
Y975081D03*
X7673Y955396D03*
Y971144D03*
Y979018D03*
Y994766D03*
X15547Y990829D03*
X25389D03*
Y998703D03*
X7673Y1002640D03*
Y1010514D03*
X15547Y1006577D03*
Y1014451D03*
Y1022325D03*
X25389Y1014451D03*
Y1022325D03*
X7673Y1026262D03*
X15551Y1065629D03*
X25393D03*
X7677Y1061692D03*
X15551Y1073503D03*
Y1081377D03*
X25393D03*
Y1089251D03*
X7677Y1077440D03*
Y1085314D03*
Y1093188D03*
X15551Y1097125D03*
Y1104999D03*
Y1112873D03*
Y1120748D03*
X25393Y1097125D03*
Y1104999D03*
Y1120748D03*
X7677Y1101062D03*
Y1116810D03*
X15551Y1136496D03*
Y1144370D03*
X25393Y1128622D03*
Y1136496D03*
Y1144370D03*
X7677Y1124684D03*
Y1132558D03*
Y1140432D03*
X15551Y1152244D03*
Y1160118D03*
X25393D03*
Y1167992D03*
X7677Y1156180D03*
Y1164055D03*
X15551Y1175866D03*
Y1183740D03*
Y1191614D03*
X25393Y1175866D03*
Y1183740D03*
X7677Y1171929D03*
Y1179803D03*
X15551Y1199488D03*
Y1215236D03*
X25393Y1199488D03*
Y1207362D03*
Y1215236D03*
X7677Y1195551D03*
Y1203425D03*
Y1211299D03*
X15551Y1223110D03*
Y1230984D03*
Y1238858D03*
X25393Y1223110D03*
Y1238858D03*
X7677Y1219173D03*
Y1234921D03*
X15551Y1254606D03*
Y1262480D03*
X25393Y1246732D03*
Y1254606D03*
X7677Y1242795D03*
Y1250669D03*
Y1258543D03*
X15551Y1270354D03*
Y1278228D03*
Y1286102D03*
X25393Y1278228D03*
X7677Y1274291D03*
X15551Y1293976D03*
Y1301850D03*
Y1309724D03*
X25393Y1293976D03*
Y1301850D03*
Y1309724D03*
X7677Y1290039D03*
Y1297913D03*
Y1305787D03*
X15551Y1317598D03*
Y1325472D03*
Y1333346D03*
X25393Y1325472D03*
Y1333346D03*
X7677Y1321535D03*
Y1329409D03*
Y1337283D03*
Y1353031D03*
X15551Y1349094D03*
X25393D03*
Y1356968D03*
X7677Y1368779D03*
Y1384527D03*
X15551Y1372716D03*
Y1380590D03*
X25393Y1364842D03*
Y1380590D03*
Y1388464D03*
X33263Y703427D03*
Y711301D03*
Y719175D03*
Y727049D03*
Y742797D03*
Y750671D03*
Y758545D03*
Y774293D03*
Y782167D03*
Y790041D03*
Y797915D03*
Y805790D03*
Y813664D03*
Y821538D03*
Y829412D03*
Y837286D03*
Y845160D03*
Y860908D03*
Y868782D03*
Y876656D03*
Y884530D03*
Y900278D03*
Y908152D03*
Y916026D03*
Y923900D03*
Y939648D03*
Y947522D03*
Y955396D03*
Y963270D03*
Y979018D03*
Y994766D03*
Y1002640D03*
Y1010514D03*
Y1026262D03*
X33267Y1061692D03*
Y1069566D03*
Y1077440D03*
Y1085314D03*
Y1101062D03*
Y1108936D03*
Y1116810D03*
Y1124684D03*
Y1140432D03*
Y1148306D03*
Y1156180D03*
Y1164055D03*
Y1179803D03*
Y1187677D03*
Y1195551D03*
Y1203425D03*
Y1219173D03*
Y1227047D03*
Y1234921D03*
Y1242795D03*
Y1258543D03*
Y1266417D03*
Y1274291D03*
Y1282165D03*
Y1290039D03*
Y1297913D03*
Y1305787D03*
Y1313661D03*
Y1321535D03*
Y1329409D03*
Y1337283D03*
Y1353031D03*
Y1368779D03*
Y1376653D03*
G54D16*
X13441Y495961D03*
X11153Y1638435D03*
X16552Y1638005D03*
X267420Y147540D03*
X263086Y147675D03*
X264516Y497341D03*
X264181Y847354D03*
X267194Y1191777D03*
X262559D03*
X276523Y147585D03*
X271943Y147630D03*
X285513Y322688D03*
X281074D03*
X289895D03*
X277776Y497341D03*
X273405D03*
X268938D03*
X274514Y672192D03*
X270109D03*
X283340D03*
X278955D03*
X268686Y847488D03*
X277788Y847237D03*
X273305D03*
X285666Y1016162D03*
X281124D03*
X290107D03*
X276807Y1191777D03*
X272082D03*
X284240Y1374544D03*
X279518Y1374543D03*
X275052Y1374715D03*
X270579Y1374626D03*
X291054Y1543211D03*
X279703Y1723398D03*
X284583Y1723465D03*
X289499Y1723735D03*
X287121Y1898327D03*
X282717D03*
X278262D03*
X273817D03*
X294506Y322688D03*
X294617Y1016162D03*
X304870Y1543211D03*
X300392D03*
X295675D03*
G54D20*
X23402Y1668874D03*
Y1718480D03*
Y1768087D03*
Y1817693D03*
X45056Y1668874D03*
Y1685410D03*
Y1701945D03*
Y1718480D03*
Y1735016D03*
Y1751551D03*
Y1768087D03*
Y1784622D03*
Y1817693D03*
Y1801158D03*
G54D25*
X64979Y35500D03*
Y45500D03*
X54979Y40500D03*
X64979Y65500D03*
X54979Y60500D03*
Y70500D03*
X64979Y171500D03*
X54979Y176500D03*
X64979Y181500D03*
Y201500D03*
X54979Y196500D03*
Y206500D03*
X64979Y244500D03*
X54979Y249500D03*
X64979Y254500D03*
Y264500D03*
Y274500D03*
X54979Y269500D03*
Y279500D03*
X64979Y380500D03*
Y390500D03*
X54979Y385500D03*
X64979Y400500D03*
Y410500D03*
X54979Y405500D03*
Y415500D03*
G54D12*
X22756Y113818D03*
X22480Y316838D03*
Y340460D03*
X22756Y1866819D03*
Y1948818D03*
Y2023818D03*
G54D36*
X307086Y1883071D03*
G54D18*
X20468Y696341D03*
Y984333D03*
X20472Y1054606D03*
Y1342598D03*
G54D10*
X29979Y30500D03*
Y75500D03*
Y166500D03*
Y211500D03*
Y239500D03*
Y284500D03*
Y375500D03*
Y420500D03*
G54D35*
X307086Y308267D03*
G54D15*
X30254Y514500D03*
Y559500D03*
Y1572504D03*
Y1617504D03*
G54D31*
X163385Y27205D03*
Y202205D03*
Y377205D03*
X163386Y552205D03*
Y727205D03*
X163385Y902205D03*
Y1077205D03*
Y1252205D03*
Y1427205D03*
Y1602205D03*
Y1777205D03*
Y1952205D03*
X373385Y32520D03*
Y207520D03*
Y382520D03*
X373386Y557520D03*
Y732520D03*
X373385Y907520D03*
Y1082520D03*
Y1257520D03*
Y1432520D03*
Y1607520D03*
Y1782520D03*
Y1957520D03*
G54D37*
X359842Y78780D03*
Y253780D03*
Y428779D03*
Y603779D03*
Y778780D03*
Y953780D03*
Y1128779D03*
Y1303780D03*
Y1478780D03*
Y1653780D03*
Y1828779D03*
Y2003780D03*
G54D19*
X15547Y723112D03*
X25389D03*
X15547Y746734D03*
X25389D03*
X7673Y734923D03*
Y766419D03*
X15547Y793979D03*
X25389D03*
X15547Y825475D03*
X25389D03*
X7673Y853034D03*
X15547Y864845D03*
X25389Y872719D03*
X7673Y884530D03*
X15547Y904215D03*
X25389Y912089D03*
X7673Y923900D03*
X15547Y943585D03*
X25389Y951459D03*
X7673Y963270D03*
X15547Y998703D03*
X7673Y1018388D03*
X25389Y1006577D03*
X15547Y1030199D03*
X25389D03*
X7677Y1069566D03*
X15551Y1089251D03*
X25393Y1073503D03*
Y1112873D03*
X7677Y1108936D03*
X15551Y1128622D03*
Y1167992D03*
X25393Y1152244D03*
X7677Y1148306D03*
X25393Y1191614D03*
X7677Y1187677D03*
X15551Y1207362D03*
X25393Y1230984D03*
X7677Y1227047D03*
X15551Y1246732D03*
X25393Y1262480D03*
Y1270354D03*
Y1286102D03*
X7677Y1266417D03*
Y1282165D03*
Y1313661D03*
X25393Y1317598D03*
X7677Y1360905D03*
X15551Y1356968D03*
X7677Y1376653D03*
X15551Y1364842D03*
X25393Y1372716D03*
X15551Y1388464D03*
X33263Y734923D03*
Y766419D03*
Y853034D03*
Y892404D03*
Y931774D03*
Y971144D03*
Y1018388D03*
X33267Y1093188D03*
Y1132558D03*
Y1171929D03*
Y1211299D03*
Y1250669D03*
Y1360905D03*
Y1384527D03*
G54D32*
X173385Y32520D03*
Y21890D03*
X183385Y32520D03*
Y21890D03*
X193385Y32520D03*
Y21890D03*
X173385Y196890D03*
X183385D03*
X193385D03*
X173385Y207520D03*
X183385D03*
X193385D03*
X173385Y371890D03*
X183385D03*
X193385D03*
X173385Y382520D03*
X183385D03*
X193385D03*
X173386Y557520D03*
Y546890D03*
X183386Y557520D03*
Y546890D03*
X193386Y557520D03*
Y546890D03*
X173386Y732520D03*
Y721890D03*
X183386Y732520D03*
Y721890D03*
X193386Y732520D03*
Y721890D03*
X173385Y896890D03*
X183385D03*
X193385D03*
X173385Y907520D03*
X183385D03*
X193385D03*
X173385Y1071890D03*
X183385D03*
X193385D03*
X173385Y1082520D03*
X183385D03*
X193385D03*
X173385Y1257520D03*
Y1246890D03*
X183385Y1257520D03*
Y1246890D03*
X193385Y1257520D03*
Y1246890D03*
X173385Y1432520D03*
Y1421890D03*
X183385Y1432520D03*
Y1421890D03*
X193385Y1432520D03*
Y1421890D03*
X173385Y1596890D03*
X183385D03*
X193385D03*
X173385Y1607520D03*
X183385D03*
X193385D03*
X173385Y1771890D03*
X183385D03*
X193385D03*
X173385Y1782520D03*
X183385D03*
X193385D03*
X173385Y1957520D03*
Y1946890D03*
X183385Y1957520D03*
Y1946890D03*
X193385Y1957520D03*
Y1946890D03*
X203385Y32520D03*
Y21890D03*
X213385Y32520D03*
Y21890D03*
X203385Y196890D03*
X213385D03*
X203385Y207520D03*
X213385D03*
X203385Y371890D03*
X213385D03*
X203385Y382520D03*
X213385D03*
X203386Y557520D03*
Y546890D03*
X213386Y557520D03*
Y546890D03*
X203386Y732520D03*
Y721890D03*
X213386Y732520D03*
Y721890D03*
X203385Y896890D03*
X213385D03*
X203385Y907520D03*
X213385D03*
X203385Y1071890D03*
X213385D03*
X203385Y1082520D03*
X213385D03*
X203385Y1257520D03*
Y1246890D03*
X213385Y1257520D03*
Y1246890D03*
X203385Y1432520D03*
Y1421890D03*
X213385Y1432520D03*
Y1421890D03*
X203385Y1596890D03*
X213385D03*
X203385Y1607520D03*
X213385D03*
X203385Y1771890D03*
X213385D03*
X203385Y1782520D03*
X213385D03*
X203385Y1957520D03*
Y1946890D03*
X213385Y1957520D03*
Y1946890D03*
X223385Y32520D03*
Y21890D03*
X233385Y32520D03*
Y21890D03*
X243385Y32520D03*
Y21890D03*
X223385Y196890D03*
X233385D03*
X243385D03*
X223385Y207520D03*
X233385D03*
X243385D03*
X223385Y371890D03*
X233385D03*
X243385D03*
X223385Y382520D03*
X233385D03*
X243385D03*
X223386Y557520D03*
Y546890D03*
X233386Y557520D03*
Y546890D03*
X243386Y557520D03*
Y546890D03*
X223386Y732520D03*
Y721890D03*
X233386Y732520D03*
Y721890D03*
X243386Y732520D03*
Y721890D03*
X223385Y896890D03*
X233385D03*
X243385D03*
X223385Y907520D03*
X233385D03*
X243385D03*
X223385Y1071890D03*
X233385D03*
X243385D03*
X223385Y1082520D03*
X233385D03*
X243385D03*
X223385Y1257520D03*
Y1246890D03*
X233385Y1257520D03*
Y1246890D03*
X243385Y1257520D03*
Y1246890D03*
X223385Y1432520D03*
Y1421890D03*
X233385Y1432520D03*
Y1421890D03*
X243385Y1432520D03*
Y1421890D03*
X223385Y1596890D03*
X233385D03*
X243385D03*
X223385Y1607520D03*
X233385D03*
X243385D03*
X223385Y1771890D03*
X233385D03*
X243385D03*
X223385Y1782520D03*
X233385D03*
X243385D03*
X223385Y1957520D03*
Y1946890D03*
X233385Y1957520D03*
Y1946890D03*
X243385Y1957520D03*
Y1946890D03*
G54D28*
X65354Y114960D03*
Y464960D03*
Y814960D03*
Y1164960D03*
Y1514960D03*
Y1864960D03*
X307086Y127165D03*
Y477165D03*
Y827165D03*
Y1343504D03*
Y1693504D03*
X307087Y2043503D03*
G54D11*
X25219Y18752D03*
X3001Y52034D03*
Y100034D03*
Y150034D03*
Y200034D03*
Y250034D03*
Y300034D03*
Y350034D03*
Y400034D03*
Y450034D03*
Y500034D03*
Y550034D03*
X10914Y578848D03*
X15984Y578849D03*
X3001Y600034D03*
Y650034D03*
Y700034D03*
Y750034D03*
Y800034D03*
Y850034D03*
Y900034D03*
Y950034D03*
Y1000034D03*
Y1050034D03*
Y1100034D03*
Y1150034D03*
Y1200034D03*
Y1250034D03*
Y1300034D03*
Y1350034D03*
Y1400034D03*
Y1450034D03*
Y1500034D03*
Y1550034D03*
X11541Y1562330D03*
X3006Y1594602D03*
X3012Y1610165D03*
X3001Y1650034D03*
Y1700034D03*
Y1750034D03*
Y1800034D03*
Y1850034D03*
Y1900034D03*
Y1950034D03*
Y2000034D03*
Y2050034D03*
X26833Y2067866D03*
X61888Y666012D03*
X57458Y1253378D03*
X54543Y1296513D03*
X63061Y1296312D03*
X67568Y1296654D03*
X54130Y1313763D03*
X55544Y1770835D03*
X55080Y1762982D03*
X54948Y1755171D03*
X56425Y1778371D03*
X70376Y1796383D03*
X75219Y18752D03*
X97417Y32853D03*
Y37438D03*
X97536Y376580D03*
X97457Y371909D03*
X97985Y391220D03*
X97643Y396024D03*
X86187Y680710D03*
X79520Y682439D03*
X88681Y704108D03*
X81563Y705437D03*
X86673Y685710D03*
X79536D03*
X98591Y720745D03*
X98564Y715937D03*
X97443Y739962D03*
X97534Y735248D03*
X98124Y745139D03*
X96904Y1067515D03*
X96948Y1092036D03*
X96949Y1087095D03*
X96774Y1072226D03*
X97403Y1424340D03*
X97825Y1419492D03*
X96993Y1443743D03*
X96996Y1438980D03*
X97465Y1447919D03*
X88837Y1771103D03*
X91460Y1765062D03*
X93771Y1748227D03*
X75376Y1796236D03*
X80376Y1796163D03*
X85376Y1796236D03*
X76833Y2067866D03*
X106335Y22580D03*
X108082Y38899D03*
X102646Y49461D03*
X104116Y82557D03*
X101990Y426104D03*
X101244Y774100D03*
X98652Y1096403D03*
X105684Y1125919D03*
X105455Y1472894D03*
X99103Y1765722D03*
X99068Y1760827D03*
X99047Y1785571D03*
X98873Y1780542D03*
X99294Y1789947D03*
X105669Y1815227D03*
X109991Y2083607D03*
X125219Y3002D03*
X162384Y56744D03*
X161742Y72497D03*
X162586Y68130D03*
X169500Y126110D03*
Y118626D03*
Y111407D03*
X166500D03*
Y118626D03*
Y126110D03*
X169329Y140623D03*
X169500Y132705D03*
X169329Y148066D03*
X166329D03*
X166500Y132705D03*
X166329Y140623D03*
X169329Y156102D03*
Y163621D03*
X166329D03*
Y156102D03*
X161377Y407575D03*
X161257Y420869D03*
X159430Y461714D03*
X156430D03*
X159430Y483012D03*
X159259Y490930D03*
X159430Y468933D03*
Y476417D03*
X156430D03*
Y468933D03*
X156259Y490930D03*
X156430Y483012D03*
X159259Y513928D03*
Y498373D03*
Y506409D03*
X156259D03*
Y498373D03*
Y513928D03*
X161826Y756757D03*
X161131Y774878D03*
X161644Y764231D03*
X158444Y822725D03*
X165872D03*
X162872D03*
X155444D03*
X165872Y830209D03*
X158444D03*
X165872Y836804D03*
X158444D03*
X165701Y844722D03*
X158273D03*
X165701Y852165D03*
X158273D03*
X155273D03*
X162701D03*
X155273Y844722D03*
X162701D03*
X155444Y836804D03*
X162872D03*
X155444Y830209D03*
X162872D03*
X165701Y860201D03*
X158273D03*
X165701Y867720D03*
X158273D03*
X155273D03*
X162701D03*
X155273Y860201D03*
X162701D03*
X164539Y1116135D03*
X162140Y1106853D03*
X156124Y1176256D03*
X163552D03*
Y1183740D03*
Y1190335D03*
X156124D03*
Y1183740D03*
X163552Y1169037D03*
X156124D03*
X153124D03*
X160552D03*
X153124Y1183740D03*
Y1190335D03*
X160552D03*
Y1183740D03*
Y1176256D03*
X153124D03*
X169375Y1183740D03*
Y1190335D03*
Y1176256D03*
X163381Y1198253D03*
X155953D03*
X152953D03*
X160381D03*
X169204D03*
X163099Y1457084D03*
X162524Y1462651D03*
X162242Y1471380D03*
X154109Y1499221D03*
X161537D03*
Y1506440D03*
X170360D03*
X154109D03*
X157109D03*
X164537D03*
Y1499221D03*
X157109D03*
X153938Y1528437D03*
X154109Y1513924D03*
Y1520519D03*
X170360Y1513924D03*
Y1520519D03*
X161537D03*
Y1513924D03*
X161366Y1528437D03*
X170189D03*
X164366D03*
X164537Y1513924D03*
Y1520519D03*
X157109D03*
Y1513924D03*
X156938Y1528437D03*
X153938Y1535880D03*
Y1543916D03*
Y1551435D03*
X170189Y1535880D03*
Y1543916D03*
X161366Y1535880D03*
Y1543916D03*
Y1551435D03*
X170189D03*
X164366D03*
Y1543916D03*
Y1535880D03*
X156938Y1551435D03*
Y1543916D03*
Y1535880D03*
X163250Y1815631D03*
X162140Y1807740D03*
X155091Y1866003D03*
X162519D03*
X159519D03*
X152091D03*
X155091Y1880706D03*
Y1887301D03*
X162519D03*
Y1880706D03*
Y1873222D03*
X155091D03*
X152091D03*
X168342D03*
X159519D03*
Y1880706D03*
Y1887301D03*
X168342D03*
Y1880706D03*
X152091Y1887301D03*
Y1880706D03*
X154920Y1902662D03*
Y1910698D03*
X162348Y1902662D03*
Y1910698D03*
X154920Y1895219D03*
X162348D03*
X168171D03*
X159348D03*
X151920D03*
X159348Y1910698D03*
Y1902662D03*
X168171Y1910698D03*
Y1902662D03*
X151920Y1910698D03*
Y1902662D03*
X154920Y1918217D03*
X162348D03*
X168171D03*
X159348D03*
X151920D03*
X159991Y2083607D03*
X175219Y3002D03*
X176928Y126110D03*
Y118626D03*
Y111407D03*
X173928D03*
Y118626D03*
Y126110D03*
X176757Y140623D03*
X176928Y132705D03*
X176757Y148066D03*
X173757D03*
X173928Y132705D03*
X173757Y140623D03*
X176757Y156102D03*
Y163621D03*
X173757D03*
Y156102D03*
X175033Y261594D03*
Y268813D03*
X178033D03*
Y261594D03*
X175033Y282892D03*
X174862Y290810D03*
Y298253D03*
X175033Y276297D03*
X178033D03*
X177862Y298253D03*
Y290810D03*
X178033Y282892D03*
X174862Y313808D03*
Y306289D03*
X177862D03*
Y313808D03*
X182191Y822725D03*
X174695D03*
X171695D03*
X179191D03*
X174524Y844722D03*
Y852165D03*
X182191Y830209D03*
X174695D03*
X182191Y836804D03*
X174695D03*
X182020Y844722D03*
Y852165D03*
X179020D03*
Y844722D03*
X171695Y836804D03*
X179191D03*
X171695Y830209D03*
X179191D03*
X171524Y852165D03*
Y844722D03*
X174524Y860201D03*
Y867720D03*
X182020Y860201D03*
Y867720D03*
X179020D03*
Y860201D03*
X171524Y867720D03*
Y860201D03*
X184284Y948331D03*
X184196Y967371D03*
X184632Y983423D03*
X184353Y1001556D03*
X184118Y1019280D03*
X188385Y1020810D03*
X179871Y1176256D03*
Y1190335D03*
Y1183740D03*
X172375Y1176256D03*
Y1190335D03*
Y1183740D03*
X176871D03*
Y1190335D03*
Y1176256D03*
X179700Y1198253D03*
X172204D03*
X176700D03*
X177856Y1506440D03*
X173360D03*
X180856D03*
X177856Y1513924D03*
Y1520519D03*
X177685Y1528437D03*
X173189D03*
X173360Y1520519D03*
Y1513924D03*
X180685Y1528437D03*
X180856Y1520519D03*
Y1513924D03*
X177685Y1535880D03*
Y1543916D03*
Y1551435D03*
X173189D03*
Y1543916D03*
Y1535880D03*
X180685Y1551435D03*
Y1543916D03*
Y1535880D03*
X178838Y1880706D03*
Y1887301D03*
Y1873222D03*
X171342Y1880706D03*
Y1887301D03*
Y1873222D03*
X175838D03*
Y1887301D03*
Y1880706D03*
X178667Y1902662D03*
Y1910698D03*
Y1895219D03*
X171171Y1902662D03*
Y1910698D03*
Y1895219D03*
X175667D03*
Y1910698D03*
Y1902662D03*
X178667Y1918217D03*
X171171D03*
X175667D03*
X219131Y1663167D03*
Y1670386D03*
Y1684465D03*
Y1677870D03*
X218960Y1692383D03*
Y1699826D03*
Y1707862D03*
Y1715381D03*
X209991Y2083607D03*
X225219Y3002D03*
X237955Y56999D03*
X240955D03*
X237955Y64483D03*
X237784Y78996D03*
X237955Y71078D03*
X240955D03*
X240784Y78996D03*
X240955Y64483D03*
X237784Y94475D03*
Y101994D03*
Y86439D03*
X240784D03*
Y101994D03*
Y94475D03*
X241033Y244995D03*
X233537D03*
X224714Y237776D03*
Y244995D03*
X227714D03*
Y237776D03*
X236537Y244995D03*
X241033Y259074D03*
X240862Y266992D03*
Y274435D03*
X241033Y252479D03*
X233537Y259074D03*
X233366Y266992D03*
Y274435D03*
X224714Y259074D03*
X224543Y266992D03*
Y274435D03*
X233537Y252479D03*
X224714D03*
X227714D03*
X236537D03*
X227543Y274435D03*
Y266992D03*
X227714Y259074D03*
X236366Y274435D03*
Y266992D03*
X236537Y259074D03*
X240862Y289990D03*
Y282471D03*
X233366Y289990D03*
X224543D03*
X233366Y282471D03*
X224543D03*
X227543D03*
X236366D03*
X227543Y289990D03*
X236366D03*
X229548Y461083D03*
X232548D03*
X238371Y482381D03*
X238200Y490299D03*
X229548Y482381D03*
X229377Y490299D03*
X238371Y468302D03*
Y475786D03*
X229548Y468302D03*
Y475786D03*
X232548D03*
Y468302D03*
X241371Y475786D03*
Y468302D03*
X232377Y490299D03*
X232548Y482381D03*
X241200Y490299D03*
X241371Y482381D03*
X238200Y513297D03*
X229377D03*
X238200Y497742D03*
X229377D03*
X238200Y505778D03*
X229377D03*
X232377D03*
X241200D03*
X232377Y497742D03*
X241200D03*
X232377Y513297D03*
X241200D03*
X227963Y608108D03*
X235391D03*
X227963Y601513D03*
X235391D03*
Y594029D03*
X227963D03*
X230963D03*
X238391D03*
Y601513D03*
X230963D03*
X238391Y608108D03*
X230963D03*
X227792Y631505D03*
X235220D03*
X227792Y623469D03*
X235220D03*
X227792Y616026D03*
X235220D03*
X238220D03*
X230792D03*
X238220Y623469D03*
X230792D03*
X238220Y631505D03*
X230792D03*
X227792Y639024D03*
X235220D03*
X238220D03*
X230792D03*
X231339Y959673D03*
X238767D03*
Y967157D03*
Y973752D03*
X231339D03*
Y967157D03*
X238767Y952454D03*
X231339D03*
X234339D03*
X241767D03*
X234339Y967157D03*
Y973752D03*
X241767D03*
Y967157D03*
Y959673D03*
X234339D03*
X238596Y981670D03*
X231168D03*
X238596Y997149D03*
Y989113D03*
X231168Y997149D03*
Y989113D03*
X234168D03*
Y997149D03*
X241596Y989113D03*
Y997149D03*
X234168Y981670D03*
X241596D03*
X238596Y1004668D03*
X231168D03*
X234168D03*
X241596D03*
X235659Y1215296D03*
X228231D03*
X235659Y1207777D03*
Y1199741D03*
X228231Y1207777D03*
Y1199741D03*
X231231D03*
Y1207777D03*
X238659Y1199741D03*
Y1207777D03*
X231231Y1215296D03*
X238659D03*
X235382Y1670386D03*
X226559Y1663167D03*
Y1670386D03*
X222131D03*
X229559D03*
Y1663167D03*
X238382Y1670386D03*
X222131Y1663167D03*
X242878Y1670386D03*
X235382Y1677870D03*
X235211Y1692383D03*
X235382Y1684465D03*
X226559D03*
Y1677870D03*
X226388Y1692383D03*
X221960D03*
X222131Y1677870D03*
Y1684465D03*
X229388Y1692383D03*
X229559Y1677870D03*
Y1684465D03*
X238382D03*
X238211Y1692383D03*
X238382Y1677870D03*
X242878D03*
Y1684465D03*
X242707Y1692383D03*
X235211Y1699826D03*
X226388D03*
X235211Y1715381D03*
Y1707862D03*
X226388D03*
Y1715381D03*
X221960D03*
Y1707862D03*
X229388Y1715381D03*
Y1707862D03*
X238211D03*
Y1715381D03*
X221960Y1699826D03*
X229388D03*
X238211D03*
X242707D03*
Y1707862D03*
Y1715381D03*
X245451Y56999D03*
X248451D03*
X245451Y64483D03*
X245280Y78996D03*
X245451Y71078D03*
X248451D03*
X248280Y78996D03*
X248451Y64483D03*
X245280Y94475D03*
Y101994D03*
Y86439D03*
X248280D03*
Y101994D03*
Y94475D03*
X267627Y115559D03*
X244033Y244995D03*
Y252479D03*
X243862Y274435D03*
Y266992D03*
X244033Y259074D03*
X243862Y282471D03*
Y289990D03*
X245867Y482381D03*
X245696Y490299D03*
X245867Y468302D03*
Y475786D03*
X248867D03*
Y468302D03*
X248696Y490299D03*
X248867Y482381D03*
X245696Y513297D03*
Y497742D03*
Y505778D03*
X248696D03*
Y497742D03*
Y513297D03*
X251710Y608108D03*
Y601513D03*
Y594029D03*
X244214Y608108D03*
Y601513D03*
Y594029D03*
X247214D03*
Y601513D03*
Y608108D03*
X254710Y594029D03*
Y601513D03*
Y608108D03*
X264433Y624321D03*
X267433D03*
X251539Y631505D03*
Y623469D03*
Y616026D03*
X244043Y631505D03*
Y623469D03*
Y616026D03*
X247043D03*
Y623469D03*
Y631505D03*
X254539Y616026D03*
Y623469D03*
Y631505D03*
X251539Y639024D03*
X244043D03*
X247043D03*
X254539D03*
X255086Y959673D03*
Y973752D03*
Y967157D03*
X247590Y959673D03*
Y973752D03*
Y967157D03*
X250590D03*
Y973752D03*
Y959673D03*
X258086Y967157D03*
Y973752D03*
Y959673D03*
X254915Y981670D03*
Y997149D03*
Y989113D03*
X247419Y981670D03*
Y997149D03*
Y989113D03*
X250419D03*
Y997149D03*
Y981670D03*
X257915Y989113D03*
Y997149D03*
Y981670D03*
X254915Y1004668D03*
X247419D03*
X250419D03*
X257915D03*
X251978Y1215296D03*
X244482D03*
X251978Y1207777D03*
Y1199741D03*
X244482Y1207777D03*
Y1199741D03*
X247482D03*
Y1207777D03*
X254978Y1199741D03*
Y1207777D03*
X247482Y1215296D03*
X254978D03*
X245878Y1670386D03*
X245707Y1692383D03*
X245878Y1684465D03*
Y1677870D03*
X245707Y1715381D03*
Y1707862D03*
Y1699826D03*
X259991Y2083607D03*
X275219Y3002D03*
X271547Y260353D03*
X276617Y256400D03*
X281193Y256624D03*
X281569Y436169D03*
X286665Y432844D03*
X291002D03*
X274991Y463099D03*
X285348Y610540D03*
X290984Y607215D03*
X276044Y624627D03*
X279044D03*
X273114Y785968D03*
X278184Y782643D03*
X282737D03*
X270070Y812192D03*
X285966Y959767D03*
X291194Y956442D03*
X282958Y1134471D03*
X288188Y1131146D03*
X283808Y1308959D03*
X289210Y1305634D03*
X275521Y1479435D03*
X279990D03*
X270234Y1482760D03*
X284086Y1659883D03*
X289421Y1656558D03*
X274704Y1723196D03*
X281066Y1834569D03*
X291550Y1829846D03*
X286623Y1829400D03*
X299687Y78778D03*
X304151D03*
X308651D03*
X313089D03*
X294483Y82732D03*
X295509Y607215D03*
X295874Y956442D03*
X292698Y1131146D03*
X294133Y1305634D03*
X313894Y1513883D03*
X294090Y1656558D03*
X293606Y1858668D03*
X314562Y2009087D03*
X309991Y2083607D03*
X325219Y3002D03*
X322005Y78778D03*
X317567D03*
X325796Y1162266D03*
X324803Y2005272D03*
X320045Y2005215D03*
X361799Y311938D03*
X354000Y652170D03*
X363169Y1329686D03*
X351391D03*
X354391D03*
X363169Y1350706D03*
Y1360043D03*
Y1340201D03*
X351391Y1350706D03*
Y1360043D03*
Y1340201D03*
X354391D03*
Y1360043D03*
Y1350706D03*
X363169Y1376210D03*
Y1367771D03*
X351391Y1376210D03*
Y1367771D03*
X354391D03*
Y1376210D03*
X352337Y1887285D03*
X359991Y2083607D03*
X375219Y3002D03*
X366169Y1329686D03*
Y1340201D03*
Y1360043D03*
Y1350706D03*
X373564Y1352548D03*
X366169Y1367771D03*
Y1376210D03*
X402512Y17108D03*
Y67108D03*
Y117108D03*
Y167108D03*
Y217108D03*
Y267108D03*
Y317108D03*
Y367108D03*
Y417108D03*
Y467108D03*
Y517108D03*
Y567108D03*
Y617108D03*
Y667108D03*
Y717108D03*
Y767108D03*
Y817108D03*
Y867108D03*
Y917108D03*
Y967108D03*
Y1017108D03*
Y1067108D03*
Y1117108D03*
Y1167108D03*
Y1217108D03*
Y1267108D03*
Y1317108D03*
Y1367108D03*
Y1417108D03*
Y1467108D03*
Y1517108D03*
Y1567108D03*
Y1617108D03*
Y1667108D03*
Y1717108D03*
Y1767108D03*
Y1817108D03*
Y1867108D03*
Y1917108D03*
Y1967108D03*
Y2017108D03*
Y2067108D03*
G54D30*
X119920Y98071D03*
Y108071D03*
Y118071D03*
Y128071D03*
Y138071D03*
Y148071D03*
Y158071D03*
Y168071D03*
Y178071D03*
Y188071D03*
Y198071D03*
Y208071D03*
Y446102D03*
Y456102D03*
Y466102D03*
Y476102D03*
Y486102D03*
Y496102D03*
Y506102D03*
Y516102D03*
Y526102D03*
Y536102D03*
Y546102D03*
Y556102D03*
Y794134D03*
Y804134D03*
Y814134D03*
Y824134D03*
Y834134D03*
Y844134D03*
Y854134D03*
Y864134D03*
Y874134D03*
Y884134D03*
Y894134D03*
Y904134D03*
Y1142165D03*
Y1152165D03*
Y1162165D03*
Y1172165D03*
Y1182165D03*
Y1192165D03*
Y1202165D03*
Y1212165D03*
Y1222165D03*
Y1232165D03*
Y1242165D03*
Y1252165D03*
Y1490197D03*
Y1500197D03*
Y1510197D03*
Y1520197D03*
Y1530197D03*
Y1540197D03*
Y1550197D03*
Y1560197D03*
Y1570197D03*
Y1580197D03*
Y1590197D03*
Y1600197D03*
Y1838228D03*
Y1848228D03*
Y1858228D03*
Y1868228D03*
Y1878228D03*
Y1888228D03*
Y1898228D03*
Y1908228D03*
Y1918228D03*
Y1928228D03*
Y1938228D03*
Y1948228D03*
X139920Y98071D03*
Y128071D03*
Y118071D03*
Y108071D03*
Y148071D03*
Y138071D03*
Y178071D03*
Y168071D03*
Y158071D03*
Y198071D03*
Y188071D03*
Y208071D03*
Y466102D03*
Y456102D03*
Y446102D03*
Y486102D03*
Y476102D03*
Y516102D03*
Y506102D03*
Y496102D03*
Y536102D03*
Y526102D03*
Y556102D03*
Y546102D03*
Y804134D03*
Y794134D03*
Y824134D03*
Y814134D03*
Y854134D03*
Y844134D03*
Y834134D03*
Y874134D03*
Y864134D03*
Y904134D03*
Y894134D03*
Y884134D03*
Y1142165D03*
Y1162165D03*
Y1152165D03*
Y1192165D03*
Y1182165D03*
Y1172165D03*
Y1212165D03*
Y1202165D03*
Y1242165D03*
Y1232165D03*
Y1222165D03*
Y1252165D03*
Y1500197D03*
Y1490197D03*
Y1530197D03*
Y1520197D03*
Y1510197D03*
Y1550197D03*
Y1540197D03*
Y1580197D03*
Y1570197D03*
Y1560197D03*
Y1600197D03*
Y1590197D03*
Y1838228D03*
Y1868228D03*
Y1858228D03*
Y1848228D03*
Y1888228D03*
Y1878228D03*
Y1918228D03*
Y1908228D03*
Y1898228D03*
Y1938228D03*
Y1928228D03*
Y1948228D03*
G54D33*
X189762Y73105D03*
X190289Y152050D03*
X190357Y247568D03*
X190817Y331786D03*
X189761Y421732D03*
X190553Y506517D03*
X192888Y598130D03*
X190816Y681645D03*
X191846Y774526D03*
X191606Y856244D03*
X196311Y947202D03*
X195516Y1032544D03*
X191250Y1122856D03*
X191342Y1206233D03*
X191846Y1299104D03*
X190552Y1380966D03*
X189463Y1474162D03*
X191079Y1557277D03*
X192143Y1648177D03*
X191607Y1731351D03*
X191530Y1823227D03*
X190289Y1900420D03*
X192125Y1998730D03*
X191530Y2043388D03*
G54D21*
X23402Y1685410D03*
Y1701945D03*
Y1735016D03*
Y1751551D03*
Y1784622D03*
Y1801158D03*
G54D26*
X64979Y55500D03*
X54979Y50500D03*
X64979Y191500D03*
X54979Y186500D03*
Y259500D03*
Y395500D03*
G54D23*
X45411Y505996D03*
Y568004D03*
Y1564000D03*
Y1626008D03*
%LPC*%
G75*
G54D38*
G01X-723776Y2987387D02*
Y-376795D01*
Y-489221D01*
X1782976D01*
Y-376795D01*
Y2987387D01*
X-723776D01*
G01X-4000Y-62500D02*
Y-137500D01*
X496000D01*
Y-62500D01*
X-4000D01*
G01X8000Y-127500D02*
Y-132500D01*
G01X6543Y-127500D02*
X9457D01*
G01X14367Y-132500D02*
X11833D01*
Y-127500D01*
X14367D01*
G01X13353Y-129917D02*
X11833D01*
G01X16933Y-127500D02*
Y-132500D01*
X19467D01*
G01X23300Y-132667D02*
X23173Y-132583D01*
Y-132417D01*
X23300Y-132333D01*
X23427Y-132417D01*
Y-132583D01*
X23300Y-132667D01*
G01Y-130417D02*
X23173Y-130333D01*
Y-130167D01*
X23300Y-130083D01*
X23427Y-130167D01*
Y-130333D01*
X23300Y-130417D01*
G01X28083Y-134167D02*
X27450Y-133333D01*
X27133Y-132500D01*
Y-129167D01*
X27450Y-128333D01*
X28083Y-127500D01*
G01X33500D02*
X32993Y-127667D01*
X32613Y-128083D01*
X32360Y-128583D01*
X32170Y-129250D01*
X32107Y-130000D01*
X32170Y-130750D01*
X32360Y-131417D01*
X32613Y-131917D01*
X32993Y-132333D01*
X33500Y-132500D01*
X34007Y-132333D01*
X34387Y-131917D01*
X34640Y-131417D01*
X34830Y-130750D01*
X34893Y-130000D01*
X34830Y-129250D01*
X34640Y-128583D01*
X34387Y-128083D01*
X34007Y-127667D01*
X33500Y-127500D01*
G01X37207Y-131500D02*
X37587Y-132083D01*
X38093Y-132417D01*
X38663Y-132500D01*
X39170Y-132417D01*
X39677Y-132000D01*
X39993Y-131500D01*
X40057Y-131000D01*
X39930Y-130417D01*
X39487Y-130000D01*
X39043Y-129833D01*
X38473D01*
G01X39043D02*
X39423Y-129583D01*
X39740Y-129167D01*
X39867Y-128667D01*
X39740Y-128167D01*
X39423Y-127750D01*
X38853Y-127500D01*
X38283Y-127583D01*
X37713Y-127917D01*
G01X44017Y-134167D02*
X44650Y-133333D01*
X44967Y-132500D01*
Y-129167D01*
X44650Y-128333D01*
X44017Y-127500D01*
G01X47407Y-131500D02*
X47787Y-132083D01*
X48293Y-132417D01*
X48863Y-132500D01*
X49370Y-132417D01*
X49877Y-132000D01*
X50193Y-131500D01*
X50257Y-131000D01*
X50130Y-130417D01*
X49687Y-130000D01*
X49243Y-129833D01*
X48673D01*
G01X49243D02*
X49623Y-129583D01*
X49940Y-129167D01*
X50067Y-128667D01*
X49940Y-128167D01*
X49623Y-127750D01*
X49053Y-127500D01*
X48483Y-127583D01*
X47913Y-127917D01*
G01X52697Y-128333D02*
X53077Y-127833D01*
X53520Y-127583D01*
X54027Y-127500D01*
X54660Y-127667D01*
X55103Y-128083D01*
X55230Y-128583D01*
X55167Y-129083D01*
X54913Y-129500D01*
X53647Y-130333D01*
X53077Y-130917D01*
X52697Y-131750D01*
X52570Y-132500D01*
X55230D01*
G01X58873D02*
X59000Y-131417D01*
X59190Y-130500D01*
X59443Y-129667D01*
X59760Y-128750D01*
X60267Y-127500D01*
X57733D01*
G01X63277Y-130833D02*
X64923D01*
G01X67997Y-128333D02*
X68377Y-127833D01*
X68820Y-127583D01*
X69327Y-127500D01*
X69960Y-127667D01*
X70403Y-128083D01*
X70530Y-128583D01*
X70467Y-129083D01*
X70213Y-129500D01*
X68947Y-130333D01*
X68377Y-130917D01*
X67997Y-131750D01*
X67870Y-132500D01*
X70530D01*
G01X72907Y-131500D02*
X73287Y-132083D01*
X73793Y-132417D01*
X74363Y-132500D01*
X74870Y-132417D01*
X75377Y-132000D01*
X75693Y-131500D01*
X75757Y-131000D01*
X75630Y-130417D01*
X75187Y-130000D01*
X74743Y-129833D01*
X74173D01*
G01X74743D02*
X75123Y-129583D01*
X75440Y-129167D01*
X75567Y-128667D01*
X75440Y-128167D01*
X75123Y-127750D01*
X74553Y-127500D01*
X73983Y-127583D01*
X73413Y-127917D01*
G01X80160Y-132500D02*
Y-127500D01*
X77817Y-131083D01*
X80983D01*
G01X83107Y-131750D02*
X83487Y-132167D01*
X83930Y-132417D01*
X84500Y-132500D01*
X85070Y-132333D01*
X85513Y-132000D01*
X85830Y-131417D01*
X85893Y-130750D01*
X85767Y-130083D01*
X85450Y-129667D01*
X85007Y-129333D01*
X84563Y-129250D01*
X84120Y-129333D01*
X83550Y-129667D01*
X83740Y-127500D01*
X85450D01*
G01X93497Y-132500D02*
Y-127500D01*
X95903D01*
G01X95017Y-129917D02*
X93497D01*
G01X98217Y-132500D02*
X99800Y-127500D01*
X101383Y-132500D01*
G01X100813Y-130750D02*
X98787D01*
G01X103570Y-132500D02*
X106230Y-127500D01*
G01X103570D02*
X106230Y-132500D01*
G01X110000Y-132667D02*
X109873Y-132583D01*
Y-132417D01*
X110000Y-132333D01*
X110127Y-132417D01*
Y-132583D01*
X110000Y-132667D01*
G01Y-130417D02*
X109873Y-130333D01*
Y-130167D01*
X110000Y-130083D01*
X110127Y-130167D01*
Y-130333D01*
X110000Y-130417D01*
G01X114783Y-134167D02*
X114150Y-133333D01*
X113833Y-132500D01*
Y-129167D01*
X114150Y-128333D01*
X114783Y-127500D01*
G01X120200D02*
X119693Y-127667D01*
X119313Y-128083D01*
X119060Y-128583D01*
X118870Y-129250D01*
X118807Y-130000D01*
X118870Y-130750D01*
X119060Y-131417D01*
X119313Y-131917D01*
X119693Y-132333D01*
X120200Y-132500D01*
X120707Y-132333D01*
X121087Y-131917D01*
X121340Y-131417D01*
X121530Y-130750D01*
X121593Y-130000D01*
X121530Y-129250D01*
X121340Y-128583D01*
X121087Y-128083D01*
X120707Y-127667D01*
X120200Y-127500D01*
G01X123907Y-131500D02*
X124287Y-132083D01*
X124793Y-132417D01*
X125363Y-132500D01*
X125870Y-132417D01*
X126377Y-132000D01*
X126693Y-131500D01*
X126757Y-131000D01*
X126630Y-130417D01*
X126187Y-130000D01*
X125743Y-129833D01*
X125173D01*
G01X125743D02*
X126123Y-129583D01*
X126440Y-129167D01*
X126567Y-128667D01*
X126440Y-128167D01*
X126123Y-127750D01*
X125553Y-127500D01*
X124983Y-127583D01*
X124413Y-127917D01*
G01X130717Y-134167D02*
X131350Y-133333D01*
X131667Y-132500D01*
Y-129167D01*
X131350Y-128333D01*
X130717Y-127500D01*
G01X134107Y-131500D02*
X134487Y-132083D01*
X134993Y-132417D01*
X135563Y-132500D01*
X136070Y-132417D01*
X136577Y-132000D01*
X136893Y-131500D01*
X136957Y-131000D01*
X136830Y-130417D01*
X136387Y-130000D01*
X135943Y-129833D01*
X135373D01*
G01X135943D02*
X136323Y-129583D01*
X136640Y-129167D01*
X136767Y-128667D01*
X136640Y-128167D01*
X136323Y-127750D01*
X135753Y-127500D01*
X135183Y-127583D01*
X134613Y-127917D01*
G01X139523Y-131917D02*
X139967Y-132333D01*
X140473Y-132500D01*
X140980Y-132333D01*
X141423Y-131833D01*
X141740Y-131083D01*
X141867Y-130333D01*
Y-129417D01*
X141740Y-128667D01*
X141423Y-128000D01*
X141043Y-127667D01*
X140600Y-127500D01*
X140093Y-127667D01*
X139713Y-128000D01*
X139460Y-128500D01*
X139333Y-129167D01*
X139460Y-129750D01*
X139777Y-130333D01*
X140157Y-130667D01*
X140600Y-130750D01*
X141107Y-130583D01*
X141487Y-130167D01*
X141867Y-129417D01*
G01X145573Y-132500D02*
X145700Y-131417D01*
X145890Y-130500D01*
X146143Y-129667D01*
X146460Y-128750D01*
X146967Y-127500D01*
X144433D01*
G01X149977Y-130833D02*
X151623D01*
G01X154507Y-131500D02*
X154887Y-132083D01*
X155393Y-132417D01*
X155963Y-132500D01*
X156470Y-132417D01*
X156977Y-132000D01*
X157293Y-131500D01*
X157357Y-131000D01*
X157230Y-130417D01*
X156787Y-130000D01*
X156343Y-129833D01*
X155773D01*
G01X156343D02*
X156723Y-129583D01*
X157040Y-129167D01*
X157167Y-128667D01*
X157040Y-128167D01*
X156723Y-127750D01*
X156153Y-127500D01*
X155583Y-127583D01*
X155013Y-127917D01*
G01X159797Y-130417D02*
X160240Y-129833D01*
X160620Y-129500D01*
X161127Y-129333D01*
X161570Y-129500D01*
X161887Y-129833D01*
X162140Y-130333D01*
X162203Y-130917D01*
X162140Y-131417D01*
X161887Y-131917D01*
X161507Y-132333D01*
X161063Y-132500D01*
X160557Y-132333D01*
X160113Y-131833D01*
X159860Y-131083D01*
X159797Y-130250D01*
X159923Y-129167D01*
X160113Y-128583D01*
X160430Y-128000D01*
X160873Y-127583D01*
X161317Y-127500D01*
X161760Y-127667D01*
X162077Y-128083D01*
G01X166100Y-132500D02*
Y-127500D01*
X165340Y-128500D01*
G01Y-132500D02*
X166860D01*
G01X171960D02*
Y-127500D01*
X169617Y-131083D01*
X172783D01*
G01X191000Y-62500D02*
Y-137500D01*
G01Y-112500D02*
X294000D01*
Y-87500D01*
G01X191000D02*
X294000D01*
G01X301507Y-122500D02*
Y-117500D01*
X302773D01*
X303280Y-117750D01*
X303660Y-118083D01*
X303977Y-118583D01*
X304230Y-119167D01*
X304293Y-120000D01*
X304230Y-120833D01*
X303977Y-121417D01*
X303660Y-121917D01*
X303280Y-122250D01*
X302773Y-122500D01*
X301507D01*
G01X306417D02*
X308000Y-117500D01*
X309583Y-122500D01*
G01X309013Y-120750D02*
X306987D01*
G01X313100Y-117500D02*
Y-122500D01*
G01X311643Y-117500D02*
X314557D01*
G01X319467Y-122500D02*
X316933D01*
Y-117500D01*
X319467D01*
G01X318453Y-119917D02*
X316933D01*
G01X323300Y-122667D02*
X323173Y-122583D01*
Y-122417D01*
X323300Y-122333D01*
X323427Y-122417D01*
Y-122583D01*
X323300Y-122667D01*
G01Y-120417D02*
X323173Y-120333D01*
Y-120167D01*
X323300Y-120083D01*
X323427Y-120167D01*
Y-120333D01*
X323300Y-120417D01*
G01X296000Y-62500D02*
Y-137500D01*
G01X294000Y-62500D02*
Y-137500D01*
G01X301633Y-97500D02*
Y-92500D01*
X303153D01*
X303660Y-92750D01*
X304040Y-93333D01*
X304167Y-94000D01*
X304040Y-94667D01*
X303723Y-95167D01*
X303153Y-95417D01*
X301633D01*
G01X306860Y-97667D02*
X309140Y-92500D01*
G01X311643Y-97500D02*
Y-92500D01*
X314557Y-97500D01*
Y-92500D01*
G01X318200Y-97667D02*
X318073Y-97583D01*
Y-97417D01*
X318200Y-97333D01*
X318327Y-97417D01*
Y-97583D01*
X318200Y-97667D01*
G01Y-95417D02*
X318073Y-95333D01*
Y-95167D01*
X318200Y-95083D01*
X318327Y-95167D01*
Y-95333D01*
X318200Y-95417D01*
G01X296000Y-112500D02*
X496000D01*
G01X301633Y-72500D02*
Y-67500D01*
X303153D01*
X303660Y-67750D01*
X304040Y-68333D01*
X304167Y-69000D01*
X304040Y-69667D01*
X303723Y-70167D01*
X303153Y-70417D01*
X301633D01*
G01X306733Y-72500D02*
Y-67500D01*
X308317D01*
X308823Y-67750D01*
X309140Y-68083D01*
X309267Y-68750D01*
X309140Y-69417D01*
X308760Y-69833D01*
X308317Y-70083D01*
X306733D01*
G01X308317D02*
X309267Y-72500D01*
G01X313100D02*
X312593Y-72417D01*
X312150Y-72083D01*
X311770Y-71583D01*
X311517Y-71000D01*
X311390Y-70333D01*
Y-69667D01*
X311517Y-69000D01*
X311770Y-68417D01*
X312150Y-67917D01*
X312593Y-67583D01*
X313100Y-67500D01*
X313607Y-67583D01*
X314050Y-67917D01*
X314430Y-68417D01*
X314683Y-69000D01*
X314810Y-69667D01*
Y-70333D01*
X314683Y-71000D01*
X314430Y-71583D01*
X314050Y-72083D01*
X313607Y-72417D01*
X313100Y-72500D01*
G01X316933Y-71500D02*
X317250Y-72000D01*
X317630Y-72333D01*
X318073Y-72500D01*
X318580Y-72333D01*
X318960Y-72000D01*
X319340Y-71500D01*
X319467Y-70833D01*
Y-67500D01*
G01X324567Y-72500D02*
X322033D01*
Y-67500D01*
X324567D01*
G01X323553Y-69917D02*
X322033D01*
G01X329793Y-67917D02*
X329413Y-67667D01*
X328970Y-67500D01*
X328463D01*
X327893Y-67750D01*
X327450Y-68167D01*
X327133Y-68667D01*
X326880Y-69500D01*
X326817Y-70250D01*
X326943Y-71000D01*
X327133Y-71500D01*
X327513Y-72000D01*
X327957Y-72333D01*
X328400Y-72500D01*
X328843D01*
X329287Y-72333D01*
X329667Y-72083D01*
X329983Y-71750D01*
G01X333500Y-67500D02*
Y-72500D01*
G01X332043Y-67500D02*
X334957D01*
G01X338600Y-72667D02*
X338473Y-72583D01*
Y-72417D01*
X338600Y-72333D01*
X338727Y-72417D01*
Y-72583D01*
X338600Y-72667D01*
G01Y-70417D02*
X338473Y-70333D01*
Y-70167D01*
X338600Y-70083D01*
X338727Y-70167D01*
Y-70333D01*
X338600Y-70417D01*
G01X296000Y-87500D02*
X496000D01*
G01X411000Y-112500D02*
Y-137500D01*
G01X416633Y-122500D02*
Y-117500D01*
X418217D01*
X418723Y-117750D01*
X419040Y-118083D01*
X419167Y-118750D01*
X419040Y-119417D01*
X418660Y-119833D01*
X418217Y-120083D01*
X416633D01*
G01X418217D02*
X419167Y-122500D01*
G01X424267D02*
X421733D01*
Y-117500D01*
X424267D01*
G01X423253Y-119917D02*
X421733D01*
G01X426517Y-117500D02*
X428100Y-122500D01*
X429683Y-117500D01*
G01X433200Y-122667D02*
X433073Y-122583D01*
Y-122417D01*
X433200Y-122333D01*
X433327Y-122417D01*
Y-122583D01*
X433200Y-122667D01*
G01Y-120417D02*
X433073Y-120333D01*
Y-120167D01*
X433200Y-120083D01*
X433327Y-120167D01*
Y-120333D01*
X433200Y-120417D01*
G01X460000Y-112500D02*
Y-137500D01*
G01X-723776Y2987387D02*
Y-376795D01*
Y-489221D01*
X1782976D01*
Y-376795D01*
Y2987387D01*
X-723776D01*
G01X6705Y-124160D02*
X7332Y-124685D01*
X8037Y-125000D01*
X8663D01*
X9290Y-124685D01*
X9760Y-124160D01*
X9995Y-123425D01*
X9838Y-122690D01*
X9447Y-122060D01*
X8742Y-121640D01*
X7802Y-121430D01*
X7253Y-121010D01*
X7018Y-120275D01*
X7175Y-119540D01*
X7567Y-119015D01*
X8115Y-118700D01*
X8663D01*
X9212Y-118910D01*
X9682Y-119435D01*
G01X13005Y-125000D02*
Y-118700D01*
G01X16295D02*
Y-125000D01*
G01Y-121850D02*
X13005D01*
G01X20010Y-118700D02*
X21890D01*
G01X20950D02*
Y-125000D01*
G01X20010D02*
X21890D01*
G01X28817D02*
X25683D01*
Y-118700D01*
X28817D01*
G01X27563Y-121745D02*
X25683D01*
G01X31748Y-125000D02*
Y-118700D01*
X35352Y-125000D01*
Y-118700D01*
G01X39693Y-126155D02*
X40007Y-124790D01*
G01X46150Y-118700D02*
Y-125000D01*
G01X44348Y-118700D02*
X47952D01*
G01X50492Y-125000D02*
X52450Y-118700D01*
X54408Y-125000D01*
G01X53703Y-122795D02*
X51197D01*
G01X57810Y-118700D02*
X59690D01*
G01X58750D02*
Y-125000D01*
G01X57810D02*
X59690D01*
G01X62700Y-118700D02*
X63797Y-125000D01*
X65050Y-118700D01*
X66303Y-125000D01*
X67400Y-118700D01*
G01X69392Y-125000D02*
X71350Y-118700D01*
X73308Y-125000D01*
G01X72603Y-122795D02*
X70097D01*
G01X75848Y-125000D02*
Y-118700D01*
X79452Y-125000D01*
Y-118700D01*
G01X88683Y-125000D02*
Y-118700D01*
X90642D01*
X91268Y-119015D01*
X91660Y-119435D01*
X91817Y-120275D01*
X91660Y-121115D01*
X91190Y-121640D01*
X90642Y-121955D01*
X88683D01*
G01X90642D02*
X91817Y-125000D01*
G01X96550Y-125210D02*
X96393Y-125105D01*
Y-124895D01*
X96550Y-124790D01*
X96707Y-124895D01*
Y-125105D01*
X96550Y-125210D01*
G01X102850Y-125000D02*
X102223Y-124895D01*
X101675Y-124475D01*
X101205Y-123845D01*
X100892Y-123110D01*
X100735Y-122270D01*
Y-121430D01*
X100892Y-120590D01*
X101205Y-119855D01*
X101675Y-119225D01*
X102223Y-118805D01*
X102850Y-118700D01*
X103477Y-118805D01*
X104025Y-119225D01*
X104495Y-119855D01*
X104808Y-120590D01*
X104965Y-121430D01*
Y-122270D01*
X104808Y-123110D01*
X104495Y-123845D01*
X104025Y-124475D01*
X103477Y-124895D01*
X102850Y-125000D01*
G01X109150Y-125210D02*
X108993Y-125105D01*
Y-124895D01*
X109150Y-124790D01*
X109307Y-124895D01*
Y-125105D01*
X109150Y-125210D01*
G01X117173Y-119225D02*
X116703Y-118910D01*
X116155Y-118700D01*
X115528D01*
X114823Y-119015D01*
X114275Y-119540D01*
X113883Y-120170D01*
X113570Y-121220D01*
X113492Y-122165D01*
X113648Y-123110D01*
X113883Y-123740D01*
X114353Y-124370D01*
X114902Y-124790D01*
X115450Y-125000D01*
X115998D01*
X116547Y-124790D01*
X117017Y-124475D01*
X117408Y-124055D01*
G01X121750Y-125210D02*
X121593Y-125105D01*
Y-124895D01*
X121750Y-124790D01*
X121907Y-124895D01*
Y-125105D01*
X121750Y-125210D01*
G01X6627Y-115000D02*
Y-108700D01*
G01X9603D02*
X6627Y-112585D01*
G01X10073Y-115000D02*
X7958Y-110800D01*
G01X12927Y-108700D02*
Y-113215D01*
X13240Y-114160D01*
X13867Y-114790D01*
X14650Y-115000D01*
X15433Y-114790D01*
X16060Y-114160D01*
X16373Y-113215D01*
Y-108700D01*
G01X22517Y-115000D02*
X19383D01*
Y-108700D01*
X22517D01*
G01X21263Y-111745D02*
X19383D01*
G01X26310Y-108700D02*
X28190D01*
G01X27250D02*
Y-115000D01*
G01X26310D02*
X28190D01*
G01X38205Y-114160D02*
X38832Y-114685D01*
X39537Y-115000D01*
X40163D01*
X40790Y-114685D01*
X41260Y-114160D01*
X41495Y-113425D01*
X41338Y-112690D01*
X40947Y-112060D01*
X40242Y-111640D01*
X39302Y-111430D01*
X38753Y-111010D01*
X38518Y-110275D01*
X38675Y-109540D01*
X39067Y-109015D01*
X39615Y-108700D01*
X40163D01*
X40712Y-108910D01*
X41182Y-109435D01*
G01X44505Y-115000D02*
Y-108700D01*
G01X47795D02*
Y-115000D01*
G01Y-111850D02*
X44505D01*
G01X50492Y-115000D02*
X52450Y-108700D01*
X54408Y-115000D01*
G01X53703Y-112795D02*
X51197D01*
G01X56948Y-115000D02*
Y-108700D01*
X60552Y-115000D01*
Y-108700D01*
G01X69705Y-115000D02*
Y-108700D01*
G01X72995D02*
Y-115000D01*
G01Y-111850D02*
X69705D01*
G01X76005Y-114160D02*
X76632Y-114685D01*
X77337Y-115000D01*
X77963D01*
X78590Y-114685D01*
X79060Y-114160D01*
X79295Y-113425D01*
X79138Y-112690D01*
X78747Y-112060D01*
X78042Y-111640D01*
X77102Y-111430D01*
X76553Y-111010D01*
X76318Y-110275D01*
X76475Y-109540D01*
X76867Y-109015D01*
X77415Y-108700D01*
X77963D01*
X78512Y-108910D01*
X78982Y-109435D01*
G01X83010Y-108700D02*
X84890D01*
G01X83950D02*
Y-115000D01*
G01X83010D02*
X84890D01*
G01X88292D02*
X90250Y-108700D01*
X92208Y-115000D01*
G01X91503Y-112795D02*
X88997D01*
G01X94748Y-115000D02*
Y-108700D01*
X98352Y-115000D01*
Y-108700D01*
G01X103320Y-111850D02*
X104887D01*
Y-113740D01*
X104417Y-114370D01*
X103868Y-114790D01*
X103085Y-115000D01*
X102302Y-114790D01*
X101753Y-114370D01*
X101283Y-113740D01*
X100970Y-113005D01*
X100813Y-112165D01*
Y-111430D01*
X100970Y-110800D01*
X101283Y-110065D01*
X101753Y-109435D01*
X102223Y-109015D01*
X102850Y-108700D01*
X103398D01*
X104025Y-108910D01*
X104495Y-109330D01*
G01X108993Y-116155D02*
X109307Y-114790D01*
G01X115450Y-108700D02*
Y-115000D01*
G01X113648Y-108700D02*
X117252D01*
G01X119792Y-115000D02*
X121750Y-108700D01*
X123708Y-115000D01*
G01X123003Y-112795D02*
X120497D01*
G01X128050Y-115000D02*
X127423Y-114895D01*
X126875Y-114475D01*
X126405Y-113845D01*
X126092Y-113110D01*
X125935Y-112270D01*
Y-111430D01*
X126092Y-110590D01*
X126405Y-109855D01*
X126875Y-109225D01*
X127423Y-108805D01*
X128050Y-108700D01*
X128677Y-108805D01*
X129225Y-109225D01*
X129695Y-109855D01*
X130008Y-110590D01*
X130165Y-111430D01*
Y-112270D01*
X130008Y-113110D01*
X129695Y-113845D01*
X129225Y-114475D01*
X128677Y-114895D01*
X128050Y-115000D01*
G01X140650D02*
Y-112165D01*
X139083Y-108700D01*
G01X142217D02*
X140650Y-112165D01*
G01X145227Y-108700D02*
Y-113215D01*
X145540Y-114160D01*
X146167Y-114790D01*
X146950Y-115000D01*
X147733Y-114790D01*
X148360Y-114160D01*
X148673Y-113215D01*
Y-108700D01*
G01X151292Y-115000D02*
X153250Y-108700D01*
X155208Y-115000D01*
G01X154503Y-112795D02*
X151997D01*
G01X157748Y-115000D02*
Y-108700D01*
X161352Y-115000D01*
Y-108700D01*
G01X30650Y-92300D02*
X28130Y-91883D01*
X25925Y-90217D01*
X24035Y-87717D01*
X22775Y-84800D01*
X22145Y-81467D01*
Y-78133D01*
X22775Y-74800D01*
X24035Y-71883D01*
X25925Y-69384D01*
X28130Y-67717D01*
X30650Y-67300D01*
X33170Y-67717D01*
X35375Y-69384D01*
X37265Y-71883D01*
X38525Y-74800D01*
X39155Y-78133D01*
Y-81467D01*
X38525Y-84800D01*
X37265Y-87717D01*
X35375Y-90217D01*
X33170Y-91883D01*
X30650Y-92300D01*
G01X33170Y-85633D02*
X36950Y-92300D01*
G01X50495Y-75634D02*
Y-87300D01*
X51755Y-90217D01*
X53645Y-91883D01*
X55850Y-92300D01*
X58055Y-91883D01*
X59945Y-90217D01*
X61205Y-87300D01*
G01Y-92300D02*
Y-75634D01*
G01X86720Y-92300D02*
Y-75634D01*
G01Y-78550D02*
X85460Y-76884D01*
X83570Y-76050D01*
X81365Y-75634D01*
X79160Y-76467D01*
X77270Y-78133D01*
X76010Y-80634D01*
X75380Y-83967D01*
X76010Y-87300D01*
X77270Y-89801D01*
X79160Y-91467D01*
X81365Y-92300D01*
X83570Y-91883D01*
X85460Y-90634D01*
X86720Y-88967D01*
G01X100895Y-92300D02*
Y-75634D01*
G01Y-79800D02*
X102155Y-77717D01*
X104045Y-76050D01*
X106565Y-75634D01*
X108770Y-76050D01*
X110660Y-77717D01*
X111605Y-80634D01*
Y-92300D01*
G01X131450Y-67300D02*
Y-92300D01*
G01X127040Y-75634D02*
X135860D01*
G01X162320Y-92300D02*
Y-75634D01*
G01Y-78550D02*
X161060Y-76884D01*
X159170Y-76050D01*
X156965Y-75634D01*
X154760Y-76467D01*
X152870Y-78133D01*
X151610Y-80634D01*
X150980Y-83967D01*
X151610Y-87300D01*
X152870Y-89801D01*
X154760Y-91467D01*
X156965Y-92300D01*
X159170Y-91883D01*
X161060Y-90634D01*
X162320Y-88967D01*
G01X6548Y-105000D02*
Y-98700D01*
X10152Y-105000D01*
Y-98700D01*
G01X14650Y-105000D02*
X14023Y-104895D01*
X13475Y-104475D01*
X13005Y-103845D01*
X12692Y-103110D01*
X12535Y-102270D01*
Y-101430D01*
X12692Y-100590D01*
X13005Y-99855D01*
X13475Y-99225D01*
X14023Y-98805D01*
X14650Y-98700D01*
X15277Y-98805D01*
X15825Y-99225D01*
X16295Y-99855D01*
X16608Y-100590D01*
X16765Y-101430D01*
Y-102270D01*
X16608Y-103110D01*
X16295Y-103845D01*
X15825Y-104475D01*
X15277Y-104895D01*
X14650Y-105000D01*
G01X20950Y-105210D02*
X20793Y-105105D01*
Y-104895D01*
X20950Y-104790D01*
X21107Y-104895D01*
Y-105105D01*
X20950Y-105210D01*
G01X27250Y-105000D02*
Y-98700D01*
X26310Y-99960D01*
G01Y-105000D02*
X28190D01*
G01X33550D02*
X34098Y-104895D01*
X34725Y-104580D01*
X35117Y-104055D01*
X35273Y-103320D01*
X35117Y-102585D01*
X34647Y-101955D01*
X33942Y-101640D01*
X33158D01*
X32688Y-101430D01*
X32297Y-100905D01*
X32140Y-100170D01*
X32375Y-99435D01*
X32923Y-98910D01*
X33550Y-98700D01*
X34177Y-98910D01*
X34725Y-99435D01*
X34960Y-100170D01*
X34803Y-100905D01*
X34412Y-101430D01*
X33942Y-101640D01*
X33158D01*
X32453Y-101955D01*
X31983Y-102585D01*
X31827Y-103320D01*
X31983Y-104055D01*
X32375Y-104580D01*
X33002Y-104895D01*
X33550Y-105000D01*
G01X39850D02*
X40398Y-104895D01*
X41025Y-104580D01*
X41417Y-104055D01*
X41573Y-103320D01*
X41417Y-102585D01*
X40947Y-101955D01*
X40242Y-101640D01*
X39458D01*
X38988Y-101430D01*
X38597Y-100905D01*
X38440Y-100170D01*
X38675Y-99435D01*
X39223Y-98910D01*
X39850Y-98700D01*
X40477Y-98910D01*
X41025Y-99435D01*
X41260Y-100170D01*
X41103Y-100905D01*
X40712Y-101430D01*
X40242Y-101640D01*
X39458D01*
X38753Y-101955D01*
X38283Y-102585D01*
X38127Y-103320D01*
X38283Y-104055D01*
X38675Y-104580D01*
X39302Y-104895D01*
X39850Y-105000D01*
G01X45993Y-106155D02*
X46307Y-104790D01*
G01X50100Y-98700D02*
X51197Y-105000D01*
X52450Y-98700D01*
X53703Y-105000D01*
X54800Y-98700D01*
G01X60317Y-105000D02*
X57183D01*
Y-98700D01*
X60317D01*
G01X59063Y-101745D02*
X57183D01*
G01X63248Y-105000D02*
Y-98700D01*
X66852Y-105000D01*
Y-98700D01*
G01X76005Y-105000D02*
Y-98700D01*
G01X79295D02*
Y-105000D01*
G01Y-101850D02*
X76005D01*
G01X81600Y-98700D02*
X82697Y-105000D01*
X83950Y-98700D01*
X85203Y-105000D01*
X86300Y-98700D01*
G01X88292Y-105000D02*
X90250Y-98700D01*
X92208Y-105000D01*
G01X91503Y-102795D02*
X88997D01*
G01X101362Y-99750D02*
X101832Y-99120D01*
X102380Y-98805D01*
X103007Y-98700D01*
X103790Y-98910D01*
X104338Y-99435D01*
X104495Y-100065D01*
X104417Y-100695D01*
X104103Y-101220D01*
X102537Y-102270D01*
X101832Y-103005D01*
X101362Y-104055D01*
X101205Y-105000D01*
X104495D01*
G01X107348D02*
Y-98700D01*
X110952Y-105000D01*
Y-98700D01*
G01X113727Y-105000D02*
Y-98700D01*
X115293D01*
X115920Y-99015D01*
X116390Y-99435D01*
X116782Y-100065D01*
X117095Y-100800D01*
X117173Y-101850D01*
X117095Y-102900D01*
X116782Y-103635D01*
X116390Y-104265D01*
X115920Y-104685D01*
X115293Y-105000D01*
X113727D01*
G01X126483D02*
Y-98700D01*
X128442D01*
X129068Y-99015D01*
X129460Y-99435D01*
X129617Y-100275D01*
X129460Y-101115D01*
X128990Y-101640D01*
X128442Y-101955D01*
X126483D01*
G01X128442D02*
X129617Y-105000D01*
G01X132627D02*
Y-98700D01*
X134193D01*
X134820Y-99015D01*
X135290Y-99435D01*
X135682Y-100065D01*
X135995Y-100800D01*
X136073Y-101850D01*
X135995Y-102900D01*
X135682Y-103635D01*
X135290Y-104265D01*
X134820Y-104685D01*
X134193Y-105000D01*
X132627D01*
G01X140650Y-105210D02*
X140493Y-105105D01*
Y-104895D01*
X140650Y-104790D01*
X140807Y-104895D01*
Y-105105D01*
X140650Y-105210D01*
G01X202000Y-72000D02*
Y-80000D01*
X206000D01*
G01X213800D02*
Y-74667D01*
G01Y-75600D02*
X213400Y-75067D01*
X212800Y-74800D01*
X212100Y-74667D01*
X211400Y-74933D01*
X210800Y-75467D01*
X210400Y-76267D01*
X210200Y-77333D01*
X210400Y-78400D01*
X210800Y-79200D01*
X211400Y-79733D01*
X212100Y-80000D01*
X212800Y-79867D01*
X213400Y-79467D01*
X213800Y-78934D01*
G01X217900Y-82400D02*
X218500Y-82667D01*
X219300Y-82400D01*
X219800Y-81867D01*
X220200Y-81200D01*
X220800Y-79067D01*
X222100Y-74667D01*
G01X218900D02*
X220800Y-79067D01*
G01X226500Y-76400D02*
X229700D01*
X229400Y-75467D01*
X228900Y-74933D01*
X228200Y-74667D01*
X227500Y-74800D01*
X226900Y-75200D01*
X226500Y-76133D01*
X226300Y-76934D01*
Y-77733D01*
X226500Y-78533D01*
X227000Y-79333D01*
X227600Y-79867D01*
X228300Y-80000D01*
X229000Y-79733D01*
X229700Y-78934D01*
G01X234600Y-80000D02*
Y-74667D01*
G01Y-75733D02*
X235100Y-75200D01*
X235600Y-74800D01*
X236300Y-74667D01*
X236800Y-74800D01*
X237400Y-75200D01*
G01X225500Y-122000D02*
Y-130000D01*
G01X223200Y-122000D02*
X227800D01*
G01X233500Y-124667D02*
Y-130000D01*
G01Y-122533D02*
X233300Y-122400D01*
Y-122133D01*
X233500Y-122000D01*
X233700Y-122133D01*
Y-122400D01*
X233500Y-122533D01*
G01X239800Y-130000D02*
Y-124667D01*
G01Y-126000D02*
X240200Y-125333D01*
X240800Y-124800D01*
X241600Y-124667D01*
X242300Y-124800D01*
X242900Y-125333D01*
X243200Y-126267D01*
Y-130000D01*
G01X251300D02*
Y-124667D01*
G01Y-125600D02*
X250900Y-125067D01*
X250300Y-124800D01*
X249600Y-124667D01*
X248900Y-124933D01*
X248300Y-125467D01*
X247900Y-126267D01*
X247700Y-127333D01*
X247900Y-128400D01*
X248300Y-129200D01*
X248900Y-129733D01*
X249600Y-130000D01*
X250300Y-129867D01*
X250900Y-129467D01*
X251300Y-128934D01*
G01X233600Y-101000D02*
X235600D01*
Y-103400D01*
X235000Y-104200D01*
X234300Y-104733D01*
X233300Y-105000D01*
X232300Y-104733D01*
X231600Y-104200D01*
X231000Y-103400D01*
X230600Y-102467D01*
X230400Y-101400D01*
Y-100467D01*
X230600Y-99667D01*
X231000Y-98733D01*
X231600Y-97933D01*
X232200Y-97400D01*
X233000Y-97000D01*
X233700D01*
X234500Y-97267D01*
X235100Y-97800D01*
G01X238700Y-105000D02*
Y-97000D01*
X243300Y-105000D01*
Y-97000D01*
G01X246800Y-105000D02*
Y-97000D01*
X248800D01*
X249600Y-97400D01*
X250200Y-97933D01*
X250700Y-98733D01*
X251100Y-99667D01*
X251200Y-101000D01*
X251100Y-102333D01*
X250700Y-103267D01*
X250200Y-104067D01*
X249600Y-104600D01*
X248800Y-105000D01*
X246800D01*
G01X257000D02*
Y-97000D01*
X255800Y-98600D01*
G01Y-105000D02*
X258200D01*
G01X255300Y-80000D02*
X255500Y-78267D01*
X255800Y-76800D01*
X256200Y-75467D01*
X256700Y-74000D01*
X257500Y-72000D01*
X253500D01*
G01X328600Y-123333D02*
X329200Y-122533D01*
X329900Y-122133D01*
X330700Y-122000D01*
X331700Y-122267D01*
X332400Y-122933D01*
X332600Y-123733D01*
X332500Y-124534D01*
X332100Y-125200D01*
X330100Y-126533D01*
X329200Y-127467D01*
X328600Y-128800D01*
X328400Y-130000D01*
X332600D01*
G01X338500Y-122000D02*
X337700Y-122267D01*
X337100Y-122933D01*
X336700Y-123733D01*
X336400Y-124800D01*
X336300Y-126000D01*
X336400Y-127200D01*
X336700Y-128267D01*
X337100Y-129067D01*
X337700Y-129733D01*
X338500Y-130000D01*
X339300Y-129733D01*
X339900Y-129067D01*
X340300Y-128267D01*
X340600Y-127200D01*
X340700Y-126000D01*
X340600Y-124800D01*
X340300Y-123733D01*
X339900Y-122933D01*
X339300Y-122267D01*
X338500Y-122000D01*
G01X346500Y-130000D02*
Y-122000D01*
X345300Y-123600D01*
G01Y-130000D02*
X347700D01*
G01X352300Y-128400D02*
X352900Y-129333D01*
X353700Y-129867D01*
X354600Y-130000D01*
X355400Y-129867D01*
X356200Y-129200D01*
X356700Y-128400D01*
X356800Y-127600D01*
X356600Y-126667D01*
X355900Y-126000D01*
X355200Y-125733D01*
X354300D01*
G01X355200D02*
X355800Y-125333D01*
X356300Y-124667D01*
X356500Y-123867D01*
X356300Y-123067D01*
X355800Y-122400D01*
X354900Y-122000D01*
X354000Y-122133D01*
X353100Y-122667D01*
G01X360700Y-130267D02*
X364300Y-122000D01*
G01X370500D02*
X369700Y-122267D01*
X369100Y-122933D01*
X368700Y-123733D01*
X368400Y-124800D01*
X368300Y-126000D01*
X368400Y-127200D01*
X368700Y-128267D01*
X369100Y-129067D01*
X369700Y-129733D01*
X370500Y-130000D01*
X371300Y-129733D01*
X371900Y-129067D01*
X372300Y-128267D01*
X372600Y-127200D01*
X372700Y-126000D01*
X372600Y-124800D01*
X372300Y-123733D01*
X371900Y-122933D01*
X371300Y-122267D01*
X370500Y-122000D01*
G01X378500Y-130000D02*
Y-122000D01*
X377300Y-123600D01*
G01Y-130000D02*
X379700D01*
G01X384700Y-130267D02*
X388300Y-122000D01*
G01X394500D02*
X393700Y-122267D01*
X393100Y-122933D01*
X392700Y-123733D01*
X392400Y-124800D01*
X392300Y-126000D01*
X392400Y-127200D01*
X392700Y-128267D01*
X393100Y-129067D01*
X393700Y-129733D01*
X394500Y-130000D01*
X395300Y-129733D01*
X395900Y-129067D01*
X396300Y-128267D01*
X396600Y-127200D01*
X396700Y-126000D01*
X396600Y-124800D01*
X396300Y-123733D01*
X395900Y-122933D01*
X395300Y-122267D01*
X394500Y-122000D01*
G01X400800Y-129067D02*
X401500Y-129733D01*
X402300Y-130000D01*
X403100Y-129733D01*
X403800Y-128934D01*
X404300Y-127733D01*
X404500Y-126533D01*
Y-125067D01*
X404300Y-123867D01*
X403800Y-122800D01*
X403200Y-122267D01*
X402500Y-122000D01*
X401700Y-122267D01*
X401100Y-122800D01*
X400700Y-123600D01*
X400500Y-124667D01*
X400700Y-125600D01*
X401200Y-126533D01*
X401800Y-127067D01*
X402500Y-127200D01*
X403300Y-126934D01*
X403900Y-126267D01*
X404500Y-125067D01*
G01X328300Y-105000D02*
Y-97000D01*
X330300D01*
X331100Y-97400D01*
X331700Y-97933D01*
X332200Y-98733D01*
X332600Y-99667D01*
X332700Y-101000D01*
X332600Y-102333D01*
X332200Y-103267D01*
X331700Y-104067D01*
X331100Y-104600D01*
X330300Y-105000D01*
X328300D01*
G01X336000D02*
X338500Y-97000D01*
X341000Y-105000D01*
G01X340100Y-102200D02*
X336900D01*
G01X346500Y-97000D02*
Y-105000D01*
G01X344200Y-97000D02*
X348800D01*
G01X352600Y-101667D02*
X353300Y-100733D01*
X353900Y-100200D01*
X354700Y-99933D01*
X355400Y-100200D01*
X355900Y-100733D01*
X356300Y-101533D01*
X356400Y-102467D01*
X356300Y-103267D01*
X355900Y-104067D01*
X355300Y-104733D01*
X354600Y-105000D01*
X353800Y-104733D01*
X353100Y-103934D01*
X352700Y-102733D01*
X352600Y-101400D01*
X352800Y-99667D01*
X353100Y-98733D01*
X353600Y-97800D01*
X354300Y-97133D01*
X355000Y-97000D01*
X355700Y-97267D01*
X356200Y-97933D01*
G01X359900Y-105000D02*
Y-97000D01*
X362500Y-103667D01*
X365100Y-97000D01*
Y-105000D01*
G01X370500Y-97000D02*
Y-105000D01*
G01X368200Y-97000D02*
X372800D01*
G01X379300Y-100733D02*
X379700Y-100333D01*
X380000Y-99667D01*
X380200Y-98733D01*
X380000Y-97933D01*
X379600Y-97400D01*
X378900Y-97000D01*
X376200D01*
Y-105000D01*
X379500D01*
X380200Y-104467D01*
X380600Y-103667D01*
X380800Y-102733D01*
X380600Y-101800D01*
X380000Y-101000D01*
X379300Y-100733D01*
X376200D01*
G01X386500Y-105000D02*
X387200Y-104867D01*
X388000Y-104467D01*
X388500Y-103800D01*
X388700Y-102867D01*
X388500Y-101934D01*
X387900Y-101133D01*
X387000Y-100733D01*
X386000D01*
X385400Y-100467D01*
X384900Y-99800D01*
X384700Y-98867D01*
X385000Y-97933D01*
X385700Y-97267D01*
X386500Y-97000D01*
X387300Y-97267D01*
X388000Y-97933D01*
X388300Y-98867D01*
X388100Y-99800D01*
X387600Y-100467D01*
X387000Y-100733D01*
X386000D01*
X385100Y-101133D01*
X384500Y-101934D01*
X384300Y-102867D01*
X384500Y-103800D01*
X385000Y-104467D01*
X385800Y-104867D01*
X386500Y-105000D01*
G01X394500D02*
X395200Y-104867D01*
X396000Y-104467D01*
X396500Y-103800D01*
X396700Y-102867D01*
X396500Y-101934D01*
X395900Y-101133D01*
X395000Y-100733D01*
X394000D01*
X393400Y-100467D01*
X392900Y-99800D01*
X392700Y-98867D01*
X393000Y-97933D01*
X393700Y-97267D01*
X394500Y-97000D01*
X395300Y-97267D01*
X396000Y-97933D01*
X396300Y-98867D01*
X396100Y-99800D01*
X395600Y-100467D01*
X395000Y-100733D01*
X394000D01*
X393100Y-101133D01*
X392500Y-101934D01*
X392300Y-102867D01*
X392500Y-103800D01*
X393000Y-104467D01*
X393800Y-104867D01*
X394500Y-105000D01*
G01X400000D02*
X402500Y-97000D01*
X405000Y-105000D01*
G01X404100Y-102200D02*
X400900D01*
G01X410500Y-97000D02*
X409700Y-97267D01*
X409100Y-97933D01*
X408700Y-98733D01*
X408400Y-99800D01*
X408300Y-101000D01*
X408400Y-102200D01*
X408700Y-103267D01*
X409100Y-104067D01*
X409700Y-104733D01*
X410500Y-105000D01*
X411300Y-104733D01*
X411900Y-104067D01*
X412300Y-103267D01*
X412600Y-102200D01*
X412700Y-101000D01*
X412600Y-99800D01*
X412300Y-98733D01*
X411900Y-97933D01*
X411300Y-97267D01*
X410500Y-97000D01*
G01X350500Y-72000D02*
Y-80000D01*
G01X348200Y-72000D02*
X352800D01*
G01X356600Y-76667D02*
X357300Y-75733D01*
X357900Y-75200D01*
X358700Y-74933D01*
X359400Y-75200D01*
X359900Y-75733D01*
X360300Y-76533D01*
X360400Y-77467D01*
X360300Y-78267D01*
X359900Y-79067D01*
X359300Y-79733D01*
X358600Y-80000D01*
X357800Y-79733D01*
X357100Y-78934D01*
X356700Y-77733D01*
X356600Y-76400D01*
X356800Y-74667D01*
X357100Y-73733D01*
X357600Y-72800D01*
X358300Y-72133D01*
X359000Y-72000D01*
X359700Y-72267D01*
X360200Y-72933D01*
G01X363900Y-80000D02*
Y-72000D01*
X366500Y-78667D01*
X369100Y-72000D01*
Y-80000D01*
G01X375100Y-76000D02*
X377100D01*
Y-78400D01*
X376500Y-79200D01*
X375800Y-79733D01*
X374800Y-80000D01*
X373800Y-79733D01*
X373100Y-79200D01*
X372500Y-78400D01*
X372100Y-77467D01*
X371900Y-76400D01*
Y-75467D01*
X372100Y-74667D01*
X372500Y-73733D01*
X373100Y-72933D01*
X373700Y-72400D01*
X374500Y-72000D01*
X375200D01*
X376000Y-72267D01*
X376600Y-72800D01*
G01X379500Y-82667D02*
X385500D01*
G01X388500Y-80000D02*
Y-72000D01*
X390900D01*
X391700Y-72400D01*
X392300Y-73333D01*
X392500Y-74400D01*
X392300Y-75467D01*
X391800Y-76267D01*
X390900Y-76667D01*
X388500D01*
G01X396300Y-80000D02*
Y-72000D01*
X398300D01*
X399100Y-72400D01*
X399700Y-72933D01*
X400200Y-73733D01*
X400600Y-74667D01*
X400700Y-76000D01*
X400600Y-77333D01*
X400200Y-78267D01*
X399700Y-79067D01*
X399100Y-79600D01*
X398300Y-80000D01*
X396300D01*
G01X407300Y-75733D02*
X407700Y-75333D01*
X408000Y-74667D01*
X408200Y-73733D01*
X408000Y-72933D01*
X407600Y-72400D01*
X406900Y-72000D01*
X404200D01*
Y-80000D01*
X407500D01*
X408200Y-79467D01*
X408600Y-78667D01*
X408800Y-77733D01*
X408600Y-76800D01*
X408000Y-76000D01*
X407300Y-75733D01*
X404200D01*
G01X411500Y-82667D02*
X417500D01*
G01X420000Y-80000D02*
X422500Y-72000D01*
X425000Y-80000D01*
G01X424100Y-77200D02*
X420900D01*
G01X427500Y-82667D02*
X433500D01*
G01X439300Y-75733D02*
X439700Y-75333D01*
X440000Y-74667D01*
X440200Y-73733D01*
X440000Y-72933D01*
X439600Y-72400D01*
X438900Y-72000D01*
X436200D01*
Y-80000D01*
X439500D01*
X440200Y-79467D01*
X440600Y-78667D01*
X440800Y-77733D01*
X440600Y-76800D01*
X440000Y-76000D01*
X439300Y-75733D01*
X436200D01*
G01X444300Y-80000D02*
Y-72000D01*
X446300D01*
X447100Y-72400D01*
X447700Y-72933D01*
X448200Y-73733D01*
X448600Y-74667D01*
X448700Y-76000D01*
X448600Y-77333D01*
X448200Y-78267D01*
X447700Y-79067D01*
X447100Y-79600D01*
X446300Y-80000D01*
X444300D01*
G01X443000Y-130000D02*
X445500Y-122000D01*
X448000Y-130000D01*
G01X447100Y-127200D02*
X443900D01*
G01X473000Y-130000D02*
Y-122000D01*
X471800Y-123600D01*
G01Y-130000D02*
X474200D01*
G01X479100Y-126667D02*
X479800Y-125733D01*
X480400Y-125200D01*
X481200Y-124933D01*
X481900Y-125200D01*
X482400Y-125733D01*
X482800Y-126533D01*
X482900Y-127467D01*
X482800Y-128267D01*
X482400Y-129067D01*
X481800Y-129733D01*
X481100Y-130000D01*
X480300Y-129733D01*
X479600Y-128934D01*
X479200Y-127733D01*
X479100Y-126400D01*
X479300Y-124667D01*
X479600Y-123733D01*
X480100Y-122800D01*
X480800Y-122133D01*
X481500Y-122000D01*
X482200Y-122267D01*
X482700Y-122933D01*
M02*
